G04 ================== begin FILE IDENTIFICATION RECORD ==================*
G04 Layout Name:  9127_F0T_Expander_BD_F_v02_0110_1240.brd*
G04 Film Name:    panel*
G04 File Format:  Gerber RS274X*
G04 File Origin:  Cadence Allegro 17.2-S081*
G04 Origin Date:  Wed Jan 11 16:06:28 2023*
G04 *
G04 Layer:  DRAWING FORMAT/TITLE_BLOCK_A*
G04 Layer:  MANUFACTURING/PHOTOPLOT_OUTLINE*
G04 Layer:  DRAWING FORMAT/TITLE_BLOCK*
G04 Layer:  DRAWING FORMAT/TITLE_DATA_PANEL*
G04 Layer:  BOARD GEOMETRY/ASSEMBLY_NOTES*
G04 *
G04 Offset:    (0.00 0.00)*
G04 Mirror:    No*
G04 Mode:      Positive*
G04 Rotation:  0*
G04 FullContactRelief:  No*
G04 UndefLineWidth:     6.00*
G04 ================== end FILE IDENTIFICATION RECORD ====================*
%FSLAX25Y25*MOIN*%
%IR0*IPPOS*OFA0.00000B0.00000*MIA0B0*SFA1.00000B1.00000*%
%ADD10C,.006*%
G75*
%LPD*%
G75*
G36*
G01X49212Y-83298D02*
G02I-1968J0D01*
G37*
G36*
G01X1775985Y1801195D02*
G02I-1969J0D01*
G37*
G36*
G01X2196081Y135084D02*
G02I-1969J0D01*
G37*
G54D10*
G01X-9843Y1820880D02*
X-80079D01*
G01X-2990Y1781510D02*
X-39390D01*
G01X-20602Y-468335D02*
Y-543335D01*
X479398D01*
Y-468335D01*
X-20602D01*
G01X-12281Y-198717D02*
X-19777Y-198476D01*
X-19702Y-196144D01*
X-19303Y-195410D01*
X-18789Y-194959D01*
X-17783Y-194805D01*
X-16790Y-195024D01*
X-16183Y-195604D01*
X-15829Y-196269D01*
X-15904Y-198601D01*
G01X-15829Y-196269D02*
X-12161Y-194986D01*
G01X-18284Y-190927D02*
X-19015Y-190343D01*
X-19369Y-189678D01*
X-19470Y-188928D01*
X-19190Y-188003D01*
X-18545Y-187370D01*
X-17789Y-187208D01*
X-17042Y-187325D01*
X-16430Y-187718D01*
X-15240Y-189624D01*
X-14393Y-190492D01*
X-13161Y-191092D01*
X-12043Y-191314D01*
X-11917Y-187396D01*
G01X-11829Y-184658D02*
X-16826Y-184497D01*
G01X-15452Y-184542D02*
X-16068Y-184242D01*
X-16552Y-183759D01*
X-16781Y-183098D01*
X-16510Y-182453D01*
X-15996Y-182003D01*
X-15362Y-181743D01*
X-11739Y-181860D01*
G01X-15362Y-181743D02*
X-15978Y-181443D01*
X-16463Y-180961D01*
X-16691Y-180300D01*
X-16421Y-179655D01*
X-15906Y-179204D01*
X-15147Y-178948D01*
X-11649Y-179061D01*
G01X-11588Y-177162D02*
X-16585Y-177001D01*
G01X-15211Y-177046D02*
X-15827Y-176746D01*
X-16311Y-176263D01*
X-16540Y-175602D01*
X-16269Y-174957D01*
X-15755Y-174507D01*
X-15121Y-174247D01*
X-11498Y-174364D01*
G01X-15121Y-174247D02*
X-15737Y-173947D01*
X-16222Y-173465D01*
X-16450Y-172804D01*
X-16180Y-172159D01*
X-15665Y-171708D01*
X-14906Y-171452D01*
X-11408Y-171565D01*
G01X-8602Y-533335D02*
Y-538335D01*
G01X-10059Y-533335D02*
X-7145D01*
G01X-2235Y-538335D02*
X-4769D01*
Y-533335D01*
X-2235D01*
G01X-3249Y-535752D02*
X-4769D01*
G01X331Y-533335D02*
Y-538335D01*
X2865D01*
G01X6698Y-538502D02*
X6571Y-538418D01*
Y-538252D01*
X6698Y-538168D01*
X6825Y-538252D01*
Y-538418D01*
X6698Y-538502D01*
G01Y-536252D02*
X6571Y-536168D01*
Y-536002D01*
X6698Y-535918D01*
X6825Y-536002D01*
Y-536168D01*
X6698Y-536252D01*
G01X11481Y-540002D02*
X10848Y-539168D01*
X10531Y-538335D01*
Y-535002D01*
X10848Y-534168D01*
X11481Y-533335D01*
G01X16898D02*
X16391Y-533502D01*
X16011Y-533918D01*
X15758Y-534418D01*
X15568Y-535085D01*
X15505Y-535835D01*
X15568Y-536585D01*
X15758Y-537252D01*
X16011Y-537752D01*
X16391Y-538168D01*
X16898Y-538335D01*
X17405Y-538168D01*
X17785Y-537752D01*
X18038Y-537252D01*
X18228Y-536585D01*
X18291Y-535835D01*
X18228Y-535085D01*
X18038Y-534418D01*
X17785Y-533918D01*
X17405Y-533502D01*
X16898Y-533335D01*
G01X20605Y-537335D02*
X20985Y-537918D01*
X21491Y-538252D01*
X22061Y-538335D01*
X22568Y-538252D01*
X23075Y-537835D01*
X23391Y-537335D01*
X23455Y-536835D01*
X23328Y-536252D01*
X22885Y-535835D01*
X22441Y-535668D01*
X21871D01*
G01X22441D02*
X22821Y-535418D01*
X23138Y-535002D01*
X23265Y-534502D01*
X23138Y-534002D01*
X22821Y-533585D01*
X22251Y-533335D01*
X21681Y-533418D01*
X21111Y-533752D01*
G01X27415Y-540002D02*
X28048Y-539168D01*
X28365Y-538335D01*
Y-535002D01*
X28048Y-534168D01*
X27415Y-533335D01*
G01X30805Y-537335D02*
X31185Y-537918D01*
X31691Y-538252D01*
X32261Y-538335D01*
X32768Y-538252D01*
X33275Y-537835D01*
X33591Y-537335D01*
X33655Y-536835D01*
X33528Y-536252D01*
X33085Y-535835D01*
X32641Y-535668D01*
X32071D01*
G01X32641D02*
X33021Y-535418D01*
X33338Y-535002D01*
X33465Y-534502D01*
X33338Y-534002D01*
X33021Y-533585D01*
X32451Y-533335D01*
X31881Y-533418D01*
X31311Y-533752D01*
G01X36095Y-534168D02*
X36475Y-533668D01*
X36918Y-533418D01*
X37425Y-533335D01*
X38058Y-533502D01*
X38501Y-533918D01*
X38628Y-534418D01*
X38565Y-534918D01*
X38311Y-535335D01*
X37045Y-536168D01*
X36475Y-536752D01*
X36095Y-537585D01*
X35968Y-538335D01*
X38628D01*
G01X42271D02*
X42398Y-537252D01*
X42588Y-536335D01*
X42841Y-535502D01*
X43158Y-534585D01*
X43665Y-533335D01*
X41131D01*
G01X46675Y-536668D02*
X48321D01*
G01X51395Y-534168D02*
X51775Y-533668D01*
X52218Y-533418D01*
X52725Y-533335D01*
X53358Y-533502D01*
X53801Y-533918D01*
X53928Y-534418D01*
X53865Y-534918D01*
X53611Y-535335D01*
X52345Y-536168D01*
X51775Y-536752D01*
X51395Y-537585D01*
X51268Y-538335D01*
X53928D01*
G01X56305Y-537335D02*
X56685Y-537918D01*
X57191Y-538252D01*
X57761Y-538335D01*
X58268Y-538252D01*
X58775Y-537835D01*
X59091Y-537335D01*
X59155Y-536835D01*
X59028Y-536252D01*
X58585Y-535835D01*
X58141Y-535668D01*
X57571D01*
G01X58141D02*
X58521Y-535418D01*
X58838Y-535002D01*
X58965Y-534502D01*
X58838Y-534002D01*
X58521Y-533585D01*
X57951Y-533335D01*
X57381Y-533418D01*
X56811Y-533752D01*
G01X63558Y-538335D02*
Y-533335D01*
X61215Y-536918D01*
X64381D01*
G01X66505Y-537585D02*
X66885Y-538002D01*
X67328Y-538252D01*
X67898Y-538335D01*
X68468Y-538168D01*
X68911Y-537835D01*
X69228Y-537252D01*
X69291Y-536585D01*
X69165Y-535918D01*
X68848Y-535502D01*
X68405Y-535168D01*
X67961Y-535085D01*
X67518Y-535168D01*
X66948Y-535502D01*
X67138Y-533335D01*
X68848D01*
G01X76895Y-538335D02*
Y-533335D01*
X79301D01*
G01X78415Y-535752D02*
X76895D01*
G01X81615Y-538335D02*
X83198Y-533335D01*
X84781Y-538335D01*
G01X84211Y-536585D02*
X82185D01*
G01X86968Y-538335D02*
X89628Y-533335D01*
G01X86968D02*
X89628Y-538335D01*
G01X93398Y-538502D02*
X93271Y-538418D01*
Y-538252D01*
X93398Y-538168D01*
X93525Y-538252D01*
Y-538418D01*
X93398Y-538502D01*
G01Y-536252D02*
X93271Y-536168D01*
Y-536002D01*
X93398Y-535918D01*
X93525Y-536002D01*
Y-536168D01*
X93398Y-536252D01*
G01X98181Y-540002D02*
X97548Y-539168D01*
X97231Y-538335D01*
Y-535002D01*
X97548Y-534168D01*
X98181Y-533335D01*
G01X103598D02*
X103091Y-533502D01*
X102711Y-533918D01*
X102458Y-534418D01*
X102268Y-535085D01*
X102205Y-535835D01*
X102268Y-536585D01*
X102458Y-537252D01*
X102711Y-537752D01*
X103091Y-538168D01*
X103598Y-538335D01*
X104105Y-538168D01*
X104485Y-537752D01*
X104738Y-537252D01*
X104928Y-536585D01*
X104991Y-535835D01*
X104928Y-535085D01*
X104738Y-534418D01*
X104485Y-533918D01*
X104105Y-533502D01*
X103598Y-533335D01*
G01X107305Y-537335D02*
X107685Y-537918D01*
X108191Y-538252D01*
X108761Y-538335D01*
X109268Y-538252D01*
X109775Y-537835D01*
X110091Y-537335D01*
X110155Y-536835D01*
X110028Y-536252D01*
X109585Y-535835D01*
X109141Y-535668D01*
X108571D01*
G01X109141D02*
X109521Y-535418D01*
X109838Y-535002D01*
X109965Y-534502D01*
X109838Y-534002D01*
X109521Y-533585D01*
X108951Y-533335D01*
X108381Y-533418D01*
X107811Y-533752D01*
G01X114115Y-540002D02*
X114748Y-539168D01*
X115065Y-538335D01*
Y-535002D01*
X114748Y-534168D01*
X114115Y-533335D01*
G01X117505Y-537335D02*
X117885Y-537918D01*
X118391Y-538252D01*
X118961Y-538335D01*
X119468Y-538252D01*
X119975Y-537835D01*
X120291Y-537335D01*
X120355Y-536835D01*
X120228Y-536252D01*
X119785Y-535835D01*
X119341Y-535668D01*
X118771D01*
G01X119341D02*
X119721Y-535418D01*
X120038Y-535002D01*
X120165Y-534502D01*
X120038Y-534002D01*
X119721Y-533585D01*
X119151Y-533335D01*
X118581Y-533418D01*
X118011Y-533752D01*
G01X122921Y-537752D02*
X123365Y-538168D01*
X123871Y-538335D01*
X124378Y-538168D01*
X124821Y-537668D01*
X125138Y-536918D01*
X125265Y-536168D01*
Y-535252D01*
X125138Y-534502D01*
X124821Y-533835D01*
X124441Y-533502D01*
X123998Y-533335D01*
X123491Y-533502D01*
X123111Y-533835D01*
X122858Y-534335D01*
X122731Y-535002D01*
X122858Y-535585D01*
X123175Y-536168D01*
X123555Y-536502D01*
X123998Y-536585D01*
X124505Y-536418D01*
X124885Y-536002D01*
X125265Y-535252D01*
G01X128971Y-538335D02*
X129098Y-537252D01*
X129288Y-536335D01*
X129541Y-535502D01*
X129858Y-534585D01*
X130365Y-533335D01*
X127831D01*
G01X133375Y-536668D02*
X135021D01*
G01X137905Y-537335D02*
X138285Y-537918D01*
X138791Y-538252D01*
X139361Y-538335D01*
X139868Y-538252D01*
X140375Y-537835D01*
X140691Y-537335D01*
X140755Y-536835D01*
X140628Y-536252D01*
X140185Y-535835D01*
X139741Y-535668D01*
X139171D01*
G01X139741D02*
X140121Y-535418D01*
X140438Y-535002D01*
X140565Y-534502D01*
X140438Y-534002D01*
X140121Y-533585D01*
X139551Y-533335D01*
X138981Y-533418D01*
X138411Y-533752D01*
G01X143195Y-536252D02*
X143638Y-535668D01*
X144018Y-535335D01*
X144525Y-535168D01*
X144968Y-535335D01*
X145285Y-535668D01*
X145538Y-536168D01*
X145601Y-536752D01*
X145538Y-537252D01*
X145285Y-537752D01*
X144905Y-538168D01*
X144461Y-538335D01*
X143955Y-538168D01*
X143511Y-537668D01*
X143258Y-536918D01*
X143195Y-536085D01*
X143321Y-535002D01*
X143511Y-534418D01*
X143828Y-533835D01*
X144271Y-533418D01*
X144715Y-533335D01*
X145158Y-533502D01*
X145475Y-533918D01*
G01X149498Y-538335D02*
Y-533335D01*
X148738Y-534335D01*
G01Y-538335D02*
X150258D01*
G01X155358D02*
Y-533335D01*
X153015Y-536918D01*
X156181D01*
G01X3643Y-101750D02*
X163Y-210006D01*
G01X5596Y-117569D02*
X3643Y-101750D01*
X677Y-117411D01*
X5596Y-117569D01*
G01X1791945Y-102983D02*
X1833071D01*
G03X1840945Y-95109I0J7874D01*
G01Y-15748D01*
G03X1833071Y-7874I-7874J0D01*
G01X1749075D01*
G02X1741201Y0I0J7874D01*
G01Y34843D01*
G03X1733327Y42717I-7874J0D01*
G01X1725453D01*
G03X1717579Y34843I0J-7874D01*
G01Y0D01*
G02X1709705Y-7874I-7874J0D01*
G01X1646713D01*
G02X1638839Y0I0J7874D01*
G01Y34843D01*
G03X1630965Y42717I-7874J0D01*
G01X1623091D01*
G03X1615217Y34843I0J-7874D01*
G01Y0D01*
G02X1607343Y-7874I-7874J0D01*
G01X1544350D01*
G02X1536476Y0I0J7874D01*
G01Y34843D01*
G03X1528602Y42717I-7874J0D01*
G01X1520728D01*
G03X1512854Y34843I0J-7874D01*
G01Y0D01*
G02X1504980Y-7874I-7874J0D01*
G01X1441988D01*
G02X1434114Y0I0J7874D01*
G01Y34843D01*
G03X1426240Y42717I-7874J0D01*
G01X1418366D01*
G03X1410492Y34843I0J-7874D01*
G01Y0D01*
G02X1402618Y-7874I-7874J0D01*
G01X1291988D01*
G02X1284114Y0I0J7874D01*
G01Y34843D01*
G03X1276240Y42717I-7874J0D01*
G01X1268366D01*
G03X1260492Y34843I0J-7874D01*
G01Y0D01*
G02X1252618Y-7874I-7874J0D01*
G01X1189626D01*
G02X1181752Y0I0J7874D01*
G01Y34843D01*
G03X1173878Y42717I-7874J0D01*
G01X1166004D01*
G03X1158130Y34843I0J-7874D01*
G01Y0D01*
G02X1150256Y-7874I-7874J0D01*
G01X1087264D01*
G02X1079390Y0I0J7874D01*
G01Y34843D01*
G03X1071516Y42717I-7874J0D01*
G01X1063642D01*
G03X1055768Y34843I0J-7874D01*
G01Y0D01*
G02X1047894Y-7874I-7874J0D01*
G01X984902D01*
G02X977028Y0I0J7874D01*
G01Y34843D01*
G03X969154Y42717I-7874J0D01*
G01X961279D01*
G03X953405Y34843I0J-7874D01*
G01Y0D01*
G02X945531Y-7874I-7874J0D01*
G01X834902D01*
G02X827028Y0I0J7874D01*
G01Y34843D01*
G03X819154Y42717I-7874J0D01*
G01X811279D01*
G03X803405Y34843I0J-7874D01*
G01Y0D01*
G02X795531Y-7874I-7874J0D01*
G01X732539D01*
G02X724665Y0I0J7874D01*
G01Y34843D01*
G03X716791Y42717I-7874J0D01*
G01X708917D01*
G03X701043Y34843I0J-7874D01*
G01Y0D01*
G02X693169Y-7874I-7874J0D01*
G01X630177D01*
G02X622303Y0I0J7874D01*
G01Y34843D01*
G03X614429Y42717I-7874J0D01*
G01X606555D01*
G03X598681Y34843I0J-7874D01*
G01Y0D01*
G02X590807Y-7874I-7874J0D01*
G01X527815D01*
G02X519941Y0I0J7874D01*
G01Y34843D01*
G03X512067Y42717I-7874J0D01*
G01X504193D01*
G03X496319Y34843I0J-7874D01*
G01Y0D01*
G02X488445Y-7874I-7874J0D01*
G01X377815D01*
G02X369941Y0I0J7874D01*
G01Y34843D01*
G03X362067Y42717I-7874J0D01*
G01X354193D01*
G03X346319Y34843I0J-7874D01*
G01Y0D01*
G02X338445Y-7874I-7874J0D01*
G01X275453D01*
G02X267579Y0I0J7874D01*
G01Y34843D01*
G03X259705Y42717I-7874J0D01*
G01X251831D01*
G03X243957Y34843I0J-7874D01*
G01Y0D01*
G02X236083Y-7874I-7874J0D01*
G01X173091D01*
G02X165217Y0I0J7874D01*
G01Y34843D01*
G03X157343Y42717I-7874J0D01*
G01X149468D01*
G03X141594Y34843I0J-7874D01*
G01Y0D01*
G02X133720Y-7874I-7874J0D01*
G01X70728D01*
G02X62854Y0I0J7874D01*
G01Y34843D01*
G03X54980Y42717I-7874J0D01*
G01X47106D01*
G03X39232Y34843I0J-7874D01*
G01Y0D01*
G02X31358Y-7874I-7874J0D01*
G01X7874D01*
G03X0Y-15748I0J-7874D01*
G01Y-95109D01*
G01X125846Y-25109D02*
X68874D01*
G03X61000Y-32983I0J-7874D01*
G01Y-95109D01*
G02X53126Y-102983I-7874J0D01*
G01X7874D01*
G02X0Y-95109I0J7874D01*
G01X795131Y1645406D02*
G03X789297Y1647992I-5834J-5287D01*
G01X7874D01*
G03X0Y1640118I0J-7874D01*
G01Y970427D01*
G03X2306Y964859I7874J0D01*
G01X12654Y954511D01*
G02X14961Y948943I-5568J-5569D01*
G01Y344836D01*
G02X12654Y339269I-7873J1D01*
G01X2306Y328920D01*
G03X0Y323353I5567J-5567D01*
G01Y7874D01*
G03X7874Y0I7874J0D01*
G01X23484D01*
G03X31358Y7874I0J7874D01*
G01Y46654D01*
G02X35295Y50591I3937J0D01*
G01X66791D01*
G02X70728Y46654I0J-3937D01*
G01Y7874D01*
G03X78602Y0I7874J0D01*
G01X125846D01*
G03X133720Y7874I0J7874D01*
G01Y46654D01*
G02X137657Y50591I3937J0D01*
G01X169154D01*
G02X173091Y46654I0J-3937D01*
G01Y7874D01*
G03X180965Y0I7874J0D01*
G01X228209D01*
G03X236083Y7874I0J7874D01*
G01Y46654D01*
G02X240020Y50591I3937J0D01*
G01X271516D01*
G02X275453Y46654I0J-3937D01*
G01Y7874D01*
G03X283327Y0I7874J0D01*
G01X330571D01*
G03X338445Y7874I0J7874D01*
G01Y46654D01*
G02X342382Y50591I3937J0D01*
G01X373878D01*
G02X377815Y46654I0J-3937D01*
G01Y7874D01*
G03X385689Y0I7874J0D01*
G01X480571D01*
G03X488445Y7874I0J7874D01*
G01Y46654D01*
G02X492382Y50591I3937J0D01*
G01X523878D01*
G02X527815Y46654I0J-3937D01*
G01Y7874D01*
G03X535689Y0I7874J0D01*
G01X582933D01*
G03X590807Y7874I0J7874D01*
G01Y46654D01*
G02X594744Y50591I3937J0D01*
G01X626240D01*
G02X630177Y46654I0J-3937D01*
G01Y7874D01*
G03X638051Y0I7874J0D01*
G01X685295D01*
G03X693169Y7874I0J7874D01*
G01Y46654D01*
G02X697106Y50591I3937J0D01*
G01X728602D01*
G02X732539Y46654I0J-3937D01*
G01Y7874D01*
G03X740413Y0I7874J0D01*
G01X787657D01*
G03X795531Y7874I0J7874D01*
G01Y46654D01*
G02X799469Y50591I3937J0D01*
G01X830965D01*
G02X834902Y46654I0J-3937D01*
G01Y7874D01*
G03X842776Y0I7874J0D01*
G01X937657D01*
G03X945531Y7874I0J7874D01*
G01Y46654D01*
G02X949469Y50591I3938J0D01*
G01X980965D01*
G02X984902Y46654I0J-3937D01*
G01Y7874D01*
G03X992776Y0I7874J0D01*
G01X1040020D01*
G03X1047894Y7874I0J7874D01*
G01Y46654D01*
G02X1051831Y50591I3937J0D01*
G01X1083327D01*
G02X1087264Y46654I0J-3937D01*
G01Y7874D01*
G03X1095138Y0I7874J0D01*
G01X1142382D01*
G03X1150256Y7874I0J7874D01*
G01Y46654D01*
G02X1154193Y50591I3937J0D01*
G01X1185689D01*
G02X1189626Y46654I0J-3937D01*
G01Y7874D01*
G03X1197500Y0I7874J0D01*
G01X1244744D01*
G03X1252618Y7874I0J7874D01*
G01Y46654D01*
G02X1256555Y50591I3937J0D01*
G01X1288051D01*
G02X1291988Y46654I0J-3937D01*
G01Y7874D01*
G03X1299862Y0I7874J0D01*
G01X1394744D01*
G03X1402618Y7874I0J7874D01*
G01Y46654D01*
G02X1406555Y50591I3937J0D01*
G01X1438051D01*
G02X1441988Y46654I0J-3937D01*
G01Y7874D01*
G03X1449862Y0I7874J0D01*
G01X1497106D01*
G03X1504980Y7874I0J7874D01*
G01Y46654D01*
G02X1508917Y50591I3937J0D01*
G01X1540413D01*
G02X1544350Y46654I0J-3937D01*
G01Y7874D01*
G03X1552224Y0I7874J0D01*
G01X1599469D01*
G03X1607343Y7874I0J7874D01*
G01Y46654D01*
G02X1611280Y50591I3937J0D01*
G01X1642776D01*
G02X1646713Y46654I0J-3937D01*
G01Y7874D01*
G03X1654587Y0I7874J0D01*
G01X1701831D01*
G03X1709705Y7874I0J7874D01*
G01Y46654D01*
G02X1713642Y50591I3937J0D01*
G01X1745138D01*
G02X1749075Y46654I0J-3937D01*
G01Y7874D01*
G03X1756949Y0I7874J0D01*
G01X1833071D01*
G03X1840945Y7874I0J7874D01*
G01Y323353D01*
G03X1838639Y328920I-7873J0D01*
G01X1828290Y339269D01*
G02X1825984Y344836I5567J5567D01*
G01Y948943D01*
G02X1828290Y954511I7874J0D01*
G01X1838639Y964859D01*
G03X1840945Y970427I-5568J5568D01*
G01Y1640118D01*
G03X1833071Y1647992I-7874J0D01*
G01X1081727D01*
G03X1075892Y1645406I-1J-7874D01*
G02X1070058Y1642819I-5835J5286D01*
G01X800966D01*
G02X795131Y1645406I0J7875D01*
G01X1840945Y1689331D02*
Y1663740D01*
G02X1833071Y1655866I-7874J0D01*
G01X1763543D01*
G02X1755669Y1663740I0J7874D01*
G01Y1689331D01*
G03X1747795Y1697205I-7874J0D01*
G01X1461575D01*
G03X1453701Y1689331I0J-7874D01*
G01Y1663740D01*
G02X1445827Y1655866I-7874J0D01*
G01X1417087D01*
G02X1409213Y1663740I0J7874D01*
G01Y1689331D01*
G03X1401339Y1697205I-7874J0D01*
G01X1115118D01*
G03X1107244Y1689331I0J-7874D01*
G01Y1663740D01*
G02X1099370Y1655866I-7874J0D01*
G01X1090079D01*
G02X1082205Y1663740I0J7874D01*
G01Y1695110D01*
G03X1074331Y1702984I-7874J0D01*
G01X796693D01*
G03X788819Y1695110I0J-7874D01*
G01Y1663740D01*
G02X780945Y1655866I-7874J0D01*
G01X741575D01*
G02X733701Y1663740I0J7874D01*
G01Y1689331D01*
G03X725827Y1697205I-7874J0D01*
G01X439607D01*
G03X431733Y1689331I0J-7874D01*
G01Y1663740D01*
G02X423859Y1655866I-7874J0D01*
G01X395118D01*
G02X387244Y1663740I0J7874D01*
G01Y1689331D01*
G03X379370Y1697205I-7874J0D01*
G01X93150D01*
G03X85276Y1689331I0J-7874D01*
G01Y1663740D01*
G02X77402Y1655866I-7874J0D01*
G01X7874D01*
G02X0Y1663740I0J7874D01*
G01Y1813006D01*
G02X7874Y1820880I7874J0D01*
G01X51000D01*
G01X0Y1830880D02*
Y1870880D01*
G01Y1830723D02*
Y1916195D01*
G01X862748Y1860880D02*
X0D01*
G01X7000Y1862380D02*
X0Y1860880D01*
X7000Y1859380D01*
Y1862380D01*
G01X39052Y1655866D02*
G03Y1647992I0J-3937D01*
G01X19366Y1655866D02*
G02Y1647992I0J-3937D01*
G01X51000Y1820880D02*
X1833071D01*
G02X1840945Y1813006I0J-7874D01*
G01Y1689331D01*
G01X63756Y-79794D02*
G03I-1575J0D01*
G01X68874Y-87668D02*
G03X61000I-3937J0D01*
G01X63756Y-79794D02*
G03I-1575J0D01*
G01X68874Y-87668D02*
G03X61000I-3937J0D01*
G01X63756Y-64046D02*
G03I-1575J0D01*
G01Y-71920D02*
G03I-1575J0D01*
G01Y-64046D02*
G03I-1575J0D01*
G01Y-71920D02*
G03I-1575J0D01*
G01Y-56172D02*
G03I-1575J0D01*
G01X68874Y-48298D02*
G02X61000I-3937J0D01*
G01X63756Y-56172D02*
G03I-1575J0D01*
G01X68874Y-48298D02*
G02X61000I-3937J0D01*
G01X76748Y-32983D02*
G03X68874Y-40857I0J-7874D01*
G01Y-95109D01*
G03X76748Y-102983I7874J0D01*
G01D02*
Y-32983D01*
G01D02*
X606748D01*
Y-102983D01*
X76748D01*
G01X89487Y0D02*
G02Y-7874I0J-3937D01*
G01X109173Y0D02*
G03Y-7874I0J-3937D01*
G01X125846Y-25109D02*
X614622D01*
G02X622496Y-32983I0J-7874D01*
G01Y-95109D01*
G03X630370Y-102983I7874J0D01*
G01X1791945D01*
G01X133874Y-32983D02*
Y-102983D01*
G01X164189Y-32983D02*
G03Y-25109I0J3937D01*
G01X174398Y-468335D02*
Y-543335D01*
G01Y-518335D02*
X277398D01*
Y-493335D01*
G01X174398D02*
X277398D01*
G01X181512Y-26290D02*
G03I-1575J0D01*
G01X173638D02*
G03I-1575J0D01*
G01X189386D02*
G03I-1575J0D01*
G01X197260D02*
G03I-1575J0D01*
G01X196926Y0D02*
G02Y-7874I0J-3937D01*
G01X203559Y-32983D02*
G02Y-25109I0J3937D01*
G01X216612Y0D02*
G03Y-7874I0J-3937D01*
G01X277398Y-468335D02*
Y-543335D01*
G01X279398Y-468335D02*
Y-543335D01*
G01X284905Y-528335D02*
Y-523335D01*
X286171D01*
X286678Y-523585D01*
X287058Y-523918D01*
X287375Y-524418D01*
X287628Y-525002D01*
X287691Y-525835D01*
X287628Y-526668D01*
X287375Y-527252D01*
X287058Y-527752D01*
X286678Y-528085D01*
X286171Y-528335D01*
X284905D01*
G01X289815D02*
X291398Y-523335D01*
X292981Y-528335D01*
G01X292411Y-526585D02*
X290385D01*
G01X296498Y-523335D02*
Y-528335D01*
G01X295041Y-523335D02*
X297955D01*
G01X302865Y-528335D02*
X300331D01*
Y-523335D01*
X302865D01*
G01X301851Y-525752D02*
X300331D01*
G01X306698Y-528502D02*
X306571Y-528418D01*
Y-528252D01*
X306698Y-528168D01*
X306825Y-528252D01*
Y-528418D01*
X306698Y-528502D01*
G01Y-526252D02*
X306571Y-526168D01*
Y-526002D01*
X306698Y-525918D01*
X306825Y-526002D01*
Y-526168D01*
X306698Y-526252D01*
G01X279398Y-518335D02*
X479398D01*
G01X285031Y-503335D02*
Y-498335D01*
X286551D01*
X287058Y-498585D01*
X287438Y-499168D01*
X287565Y-499835D01*
X287438Y-500502D01*
X287121Y-501002D01*
X286551Y-501252D01*
X285031D01*
G01X290258Y-503502D02*
X292538Y-498335D01*
G01X295041Y-503335D02*
Y-498335D01*
X297955Y-503335D01*
Y-498335D01*
G01X301598Y-503502D02*
X301471Y-503418D01*
Y-503252D01*
X301598Y-503168D01*
X301725Y-503252D01*
Y-503418D01*
X301598Y-503502D01*
G01Y-501252D02*
X301471Y-501168D01*
Y-501002D01*
X301598Y-500918D01*
X301725Y-501002D01*
Y-501168D01*
X301598Y-501252D01*
G01X279398Y-493335D02*
X479398D01*
G01X285031Y-478335D02*
Y-473335D01*
X286551D01*
X287058Y-473585D01*
X287438Y-474168D01*
X287565Y-474835D01*
X287438Y-475502D01*
X287121Y-476002D01*
X286551Y-476252D01*
X285031D01*
G01X290131Y-478335D02*
Y-473335D01*
X291715D01*
X292221Y-473585D01*
X292538Y-473918D01*
X292665Y-474585D01*
X292538Y-475252D01*
X292158Y-475668D01*
X291715Y-475918D01*
X290131D01*
G01X291715D02*
X292665Y-478335D01*
G01X296498D02*
X295991Y-478252D01*
X295548Y-477918D01*
X295168Y-477418D01*
X294915Y-476835D01*
X294788Y-476168D01*
Y-475502D01*
X294915Y-474835D01*
X295168Y-474252D01*
X295548Y-473752D01*
X295991Y-473418D01*
X296498Y-473335D01*
X297005Y-473418D01*
X297448Y-473752D01*
X297828Y-474252D01*
X298081Y-474835D01*
X298208Y-475502D01*
Y-476168D01*
X298081Y-476835D01*
X297828Y-477418D01*
X297448Y-477918D01*
X297005Y-478252D01*
X296498Y-478335D01*
G01X300331Y-477335D02*
X300648Y-477835D01*
X301028Y-478168D01*
X301471Y-478335D01*
X301978Y-478168D01*
X302358Y-477835D01*
X302738Y-477335D01*
X302865Y-476668D01*
Y-473335D01*
G01X307965Y-478335D02*
X305431D01*
Y-473335D01*
X307965D01*
G01X306951Y-475752D02*
X305431D01*
G01X313191Y-473752D02*
X312811Y-473502D01*
X312368Y-473335D01*
X311861D01*
X311291Y-473585D01*
X310848Y-474002D01*
X310531Y-474502D01*
X310278Y-475335D01*
X310215Y-476085D01*
X310341Y-476835D01*
X310531Y-477335D01*
X310911Y-477835D01*
X311355Y-478168D01*
X311798Y-478335D01*
X312241D01*
X312685Y-478168D01*
X313065Y-477918D01*
X313381Y-477585D01*
G01X316898Y-473335D02*
Y-478335D01*
G01X315441Y-473335D02*
X318355D01*
G01X321998Y-478502D02*
X321871Y-478418D01*
Y-478252D01*
X321998Y-478168D01*
X322125Y-478252D01*
Y-478418D01*
X321998Y-478502D01*
G01Y-476252D02*
X321871Y-476168D01*
Y-476002D01*
X321998Y-475918D01*
X322125Y-476002D01*
Y-476168D01*
X321998Y-476252D01*
G01X292013Y0D02*
G02Y-7874I0J-3937D01*
G01X311699Y0D02*
G03Y-7874I0J-3937D01*
G01X394258Y-543563D02*
Y-518563D01*
G01X397031Y-520835D02*
Y-525835D01*
X399565D01*
G01X402638Y-520835D02*
X404158D01*
G01X403398D02*
Y-525835D01*
G01X402638D02*
X404158D01*
G01X409005Y-523168D02*
X409258Y-522918D01*
X409448Y-522502D01*
X409575Y-521918D01*
X409448Y-521418D01*
X409195Y-521085D01*
X408751Y-520835D01*
X407041D01*
Y-525835D01*
X409131D01*
X409575Y-525502D01*
X409828Y-525002D01*
X409955Y-524418D01*
X409828Y-523835D01*
X409448Y-523335D01*
X409005Y-523168D01*
X407041D01*
G01X413598Y-526002D02*
X413471Y-525918D01*
Y-525752D01*
X413598Y-525668D01*
X413725Y-525752D01*
Y-525918D01*
X413598Y-526002D01*
G01Y-523752D02*
X413471Y-523668D01*
Y-523502D01*
X413598Y-523418D01*
X413725Y-523502D01*
Y-523668D01*
X413598Y-523752D01*
G01X400760Y1655866D02*
G02Y1647992I0J-3937D01*
G01X420446Y1655866D02*
G03Y1647992I0J-3937D01*
G01X437258Y-518563D02*
Y-543563D01*
G01X437398Y-518335D02*
Y-543335D01*
G01X441298Y-520835D02*
Y-525835D01*
G01X439841Y-520835D02*
X442755D01*
G01X446398Y-525835D02*
X446018Y-525752D01*
X445638Y-525418D01*
X445385Y-524835D01*
X445258Y-524168D01*
X445385Y-523502D01*
X445638Y-522918D01*
X446018Y-522585D01*
X446398Y-522502D01*
X446778Y-522585D01*
X447158Y-522918D01*
X447411Y-523502D01*
X447475Y-524168D01*
X447411Y-524835D01*
X447158Y-525418D01*
X446778Y-525752D01*
X446398Y-525835D01*
G01X451498D02*
X451118Y-525752D01*
X450738Y-525418D01*
X450485Y-524835D01*
X450358Y-524168D01*
X450485Y-523502D01*
X450738Y-522918D01*
X451118Y-522585D01*
X451498Y-522502D01*
X451878Y-522585D01*
X452258Y-522918D01*
X452511Y-523502D01*
X452575Y-524168D01*
X452511Y-524835D01*
X452258Y-525418D01*
X451878Y-525752D01*
X451498Y-525835D01*
G01X456598D02*
Y-520835D01*
G01X461698Y-526002D02*
X461571Y-525918D01*
Y-525752D01*
X461698Y-525668D01*
X461825Y-525752D01*
Y-525918D01*
X461698Y-526002D01*
G01Y-523752D02*
X461571Y-523668D01*
Y-523502D01*
X461698Y-523418D01*
X461825Y-523502D01*
Y-523668D01*
X461698Y-523752D01*
G01X437398Y-493335D02*
Y-518335D01*
G01X440031Y-500835D02*
Y-495835D01*
X441615D01*
X442121Y-496085D01*
X442438Y-496418D01*
X442565Y-497085D01*
X442438Y-497752D01*
X442058Y-498168D01*
X441615Y-498418D01*
X440031D01*
G01X441615D02*
X442565Y-500835D01*
G01X447665D02*
X445131D01*
Y-495835D01*
X447665D01*
G01X446651Y-498252D02*
X445131D01*
G01X449915Y-495835D02*
X451498Y-500835D01*
X453081Y-495835D01*
G01X456598Y-501002D02*
X456471Y-500918D01*
Y-500752D01*
X456598Y-500668D01*
X456725Y-500752D01*
Y-500918D01*
X456598Y-501002D01*
G01Y-498752D02*
X456471Y-498668D01*
Y-498502D01*
X456598Y-498418D01*
X456725Y-498502D01*
Y-498668D01*
X456598Y-498752D01*
G01X427034Y0D02*
G02Y-7874I0J-3937D01*
G01X445411Y-546502D02*
X445518Y-546377D01*
X445598Y-546168D01*
X445651Y-545877D01*
X445598Y-545627D01*
X445491Y-545460D01*
X445305Y-545335D01*
X444585D01*
Y-547835D01*
X445465D01*
X445651Y-547668D01*
X445758Y-547418D01*
X445811Y-547127D01*
X445758Y-546835D01*
X445598Y-546585D01*
X445411Y-546502D01*
X444585D01*
G01X447878Y-547835D02*
Y-546168D01*
G01Y-546460D02*
X447771Y-546293D01*
X447611Y-546210D01*
X447425Y-546168D01*
X447238Y-546252D01*
X447078Y-546418D01*
X446971Y-546668D01*
X446918Y-547002D01*
X446971Y-547335D01*
X447078Y-547585D01*
X447238Y-547752D01*
X447425Y-547835D01*
X447611Y-547793D01*
X447771Y-547668D01*
X447878Y-547502D01*
G01X449198Y-547543D02*
X449331Y-547710D01*
X449518Y-547835D01*
X449678D01*
X449838Y-547752D01*
X449945Y-547627D01*
X449998Y-547460D01*
X449971Y-547210D01*
X449865Y-547085D01*
X449385Y-546835D01*
X449278Y-546543D01*
X449331Y-546335D01*
X449438Y-546210D01*
X449598Y-546168D01*
X449758Y-546210D01*
X449918Y-546335D01*
G01X451398Y-546710D02*
X452251D01*
X452171Y-546418D01*
X452038Y-546252D01*
X451851Y-546168D01*
X451665Y-546210D01*
X451505Y-546335D01*
X451398Y-546627D01*
X451345Y-546877D01*
Y-547127D01*
X451398Y-547377D01*
X451531Y-547627D01*
X451691Y-547793D01*
X451878Y-547835D01*
X452065Y-547752D01*
X452251Y-547502D01*
G01X453518Y-547835D02*
Y-545335D01*
G01Y-546585D02*
X453651Y-546335D01*
X453811Y-546210D01*
X453971Y-546168D01*
X454211Y-546252D01*
X454371Y-546418D01*
X454478Y-546710D01*
Y-547043D01*
X454425Y-547377D01*
X454318Y-547627D01*
X454131Y-547793D01*
X453971Y-547835D01*
X453811Y-547793D01*
X453651Y-547668D01*
X453518Y-547460D01*
G01X456198Y-547835D02*
X456038Y-547793D01*
X455878Y-547627D01*
X455771Y-547335D01*
X455718Y-547002D01*
X455771Y-546668D01*
X455878Y-546377D01*
X456038Y-546210D01*
X456198Y-546168D01*
X456358Y-546210D01*
X456518Y-546377D01*
X456625Y-546668D01*
X456651Y-547002D01*
X456625Y-547335D01*
X456518Y-547627D01*
X456358Y-547793D01*
X456198Y-547835D01*
G01X458878D02*
Y-546168D01*
G01Y-546460D02*
X458771Y-546293D01*
X458611Y-546210D01*
X458425Y-546168D01*
X458238Y-546252D01*
X458078Y-546418D01*
X457971Y-546668D01*
X457918Y-547002D01*
X457971Y-547335D01*
X458078Y-547585D01*
X458238Y-547752D01*
X458425Y-547835D01*
X458611Y-547793D01*
X458771Y-547668D01*
X458878Y-547502D01*
G01X460225Y-547835D02*
Y-546168D01*
G01Y-546502D02*
X460358Y-546335D01*
X460491Y-546210D01*
X460678Y-546168D01*
X460811Y-546210D01*
X460971Y-546335D01*
G01X463278Y-545335D02*
Y-547835D01*
G01Y-547460D02*
X463171Y-547668D01*
X463011Y-547793D01*
X462825Y-547835D01*
X462611Y-547752D01*
X462451Y-547543D01*
X462345Y-547293D01*
X462318Y-547002D01*
X462345Y-546710D01*
X462451Y-546460D01*
X462611Y-546252D01*
X462825Y-546168D01*
X463011Y-546210D01*
X463145Y-546293D01*
X463278Y-546460D01*
G01X466665Y-547835D02*
Y-545335D01*
X467331D01*
X467545Y-545460D01*
X467678Y-545627D01*
X467731Y-545960D01*
X467678Y-546293D01*
X467518Y-546502D01*
X467331Y-546627D01*
X466665D01*
G01X467331D02*
X467731Y-547835D01*
G01X468998Y-546710D02*
X469851D01*
X469771Y-546418D01*
X469638Y-546252D01*
X469451Y-546168D01*
X469265Y-546210D01*
X469105Y-546335D01*
X468998Y-546627D01*
X468945Y-546877D01*
Y-547127D01*
X468998Y-547377D01*
X469131Y-547627D01*
X469291Y-547793D01*
X469478Y-547835D01*
X469665Y-547752D01*
X469851Y-547502D01*
G01X471118Y-546168D02*
X471598Y-547835D01*
X472078Y-546168D01*
G01X473798Y-547918D02*
X473745Y-547877D01*
Y-547793D01*
X473798Y-547752D01*
X473851Y-547793D01*
Y-547877D01*
X473798Y-547918D01*
G01X475545Y-547543D02*
X475731Y-547752D01*
X475945Y-547835D01*
X476158Y-547752D01*
X476345Y-547502D01*
X476478Y-547127D01*
X476531Y-546752D01*
Y-546293D01*
X476478Y-545918D01*
X476345Y-545585D01*
X476185Y-545418D01*
X475998Y-545335D01*
X475785Y-545418D01*
X475625Y-545585D01*
X475518Y-545835D01*
X475465Y-546168D01*
X475518Y-546460D01*
X475651Y-546752D01*
X475811Y-546918D01*
X475998Y-546960D01*
X476211Y-546877D01*
X476371Y-546668D01*
X476531Y-546293D01*
G01X478411Y-546502D02*
X478518Y-546377D01*
X478598Y-546168D01*
X478651Y-545877D01*
X478598Y-545627D01*
X478491Y-545460D01*
X478305Y-545335D01*
X477585D01*
Y-547835D01*
X478465D01*
X478651Y-547668D01*
X478758Y-547418D01*
X478811Y-547127D01*
X478758Y-546835D01*
X478598Y-546585D01*
X478411Y-546502D01*
X477585D01*
G01X446720Y0D02*
G03Y-7874I0J-3937D01*
G01X464189Y-32983D02*
G03Y-25109I0J3937D01*
G01X473638Y-26290D02*
G03I-1575J0D01*
G01X489386D02*
G03I-1575J0D01*
G01X481512D02*
G03I-1575J0D01*
G01X503559Y-32983D02*
G02Y-25109I0J3937D01*
G01X497260Y-26290D02*
G03I-1575J0D01*
G01X541748Y-102983D02*
Y-32983D01*
G01X550894Y0D02*
G02Y-7874I0J-3937D01*
G01X570580Y0D02*
G03Y-7874I0J-3937D01*
G01X606748Y-32983D02*
G02X614622Y-40857I0J-7874D01*
G01Y-95109D01*
G02X606748Y-102983I-7874J0D01*
G01X622890Y-79794D02*
G03I-1575J0D01*
G01X614622Y-87668D02*
G02X622496I3937J0D01*
G01X622890Y-71920D02*
G03I-1575J0D01*
G01Y-64046D02*
G03I-1575J0D01*
G01Y-56172D02*
G03I-1575J0D01*
G01X614622Y-48298D02*
G03X622496I3937J0D01*
G01X614622Y-25109D02*
G02X622496Y-32983I0J-7874D01*
G01Y-95109D02*
G03X630370Y-102983I7874J0D01*
G01X751842Y0D02*
G02Y-7874I0J-3937D01*
G01X750976Y1655866D02*
G02Y1647992I0J-3937D01*
G01X771528Y0D02*
G03Y-7874I0J-3937D01*
G01X770662Y1655866D02*
G03Y1647992I0J-3937D01*
G01X886523Y1842130D02*
X881873D01*
Y1854630D01*
X886523D01*
G01X954723Y1842130D02*
X959373D01*
Y1854630D01*
X954723D01*
G01X978198Y1860880D02*
X1840945D01*
G01X1011688Y0D02*
G02Y-7874I0J-3937D01*
G01X1031374Y0D02*
G03Y-7874I0J-3937D01*
G01X1082205Y1655866D02*
X1081727D01*
G01X1211196Y0D02*
G02Y-7874I0J-3937D01*
G01X1230882Y0D02*
G03Y-7874I0J-3937D01*
G01X1337940Y0D02*
G02Y-7874I0J-3937D01*
G01X1357626Y0D02*
G03Y-7874I0J-3937D01*
G01X1423112Y1655866D02*
G02Y1647992I0J-3937D01*
G01X1442798Y1655866D02*
G03Y1647992I0J-3937D01*
G01X1469018Y0D02*
G02Y-7874I0J-3937D01*
G01X1488704Y0D02*
G03Y-7874I0J-3937D01*
G01X1667656Y0D02*
G02Y-7874I0J-3937D01*
G01X1687342Y0D02*
G03Y-7874I0J-3937D01*
G01X1799311Y1655866D02*
G02Y1647992I0J-3937D01*
G01X1818997Y1655866D02*
G03Y1647992I0J-3937D01*
G01X1833945Y1859380D02*
X1840945Y1860880D01*
X1833945Y1862380D01*
Y1859380D01*
G01X1850945Y-102983D02*
X1890945D01*
G01X1850945Y1820880D02*
X1890945D01*
G01X1840945Y1830880D02*
Y1870880D01*
G01Y1830723D02*
Y1870510D01*
G01X1880945Y801224D02*
Y-102983D01*
G01X1879445Y-95983D02*
X1880945Y-102983D01*
X1882445Y-95983D01*
X1879445D01*
G01X1880945Y916674D02*
Y1820880D01*
G01X1882445Y1813880D02*
X1880945Y1820880D01*
X1879445Y1813880D01*
X1882445D01*
G01X1899695Y818799D02*
Y814149D01*
X1887195D01*
Y818799D01*
G01X1899695Y899399D02*
Y904049D01*
X1887195D01*
Y899399D01*
G01X2166834Y96413D02*
X2167087Y96663D01*
X2167277Y97079D01*
X2167404Y97663D01*
X2167277Y98163D01*
X2167024Y98496D01*
X2166580Y98746D01*
X2164870D01*
Y93746D01*
X2166960D01*
X2167404Y94079D01*
X2167657Y94579D01*
X2167784Y95163D01*
X2167657Y95746D01*
X2167277Y96246D01*
X2166834Y96413D01*
X2164870D01*
G01X2170540Y93746D02*
Y97079D01*
G01Y96413D02*
X2170857Y96746D01*
X2171174Y96996D01*
X2171617Y97079D01*
X2171934Y96996D01*
X2172314Y96746D01*
G01X2175577Y95996D02*
X2177604D01*
X2177414Y96579D01*
X2177097Y96913D01*
X2176654Y97079D01*
X2176210Y96996D01*
X2175830Y96746D01*
X2175577Y96163D01*
X2175450Y95663D01*
Y95163D01*
X2175577Y94663D01*
X2175894Y94163D01*
X2176274Y93829D01*
X2176717Y93746D01*
X2177160Y93913D01*
X2177604Y94413D01*
G01X2182767Y93746D02*
Y97079D01*
G01Y96496D02*
X2182514Y96829D01*
X2182134Y96996D01*
X2181690Y97079D01*
X2181247Y96913D01*
X2180867Y96579D01*
X2180614Y96079D01*
X2180487Y95413D01*
X2180614Y94746D01*
X2180867Y94246D01*
X2181247Y93913D01*
X2181690Y93746D01*
X2182134Y93829D01*
X2182514Y94079D01*
X2182767Y94413D01*
G01X2185650Y93746D02*
Y98746D01*
G01X2187677Y97079D02*
X2185650Y95163D01*
G01X2186474Y95913D02*
X2187804Y93746D01*
G01X2191827Y98746D02*
Y93746D01*
G01X2190940Y97079D02*
X2192714D01*
G01X2198067Y93746D02*
Y97079D01*
G01Y96496D02*
X2197814Y96829D01*
X2197434Y96996D01*
X2196990Y97079D01*
X2196547Y96913D01*
X2196167Y96579D01*
X2195914Y96079D01*
X2195787Y95413D01*
X2195914Y94746D01*
X2196167Y94246D01*
X2196547Y93913D01*
X2196990Y93746D01*
X2197434Y93829D01*
X2197814Y94079D01*
X2198067Y94413D01*
G01X2200887Y93746D02*
Y98746D01*
G01Y96246D02*
X2201204Y96746D01*
X2201584Y96996D01*
X2201964Y97079D01*
X2202534Y96913D01*
X2202914Y96579D01*
X2203167Y95996D01*
Y95329D01*
X2203040Y94663D01*
X2202787Y94163D01*
X2202344Y93829D01*
X2201964Y93746D01*
X2201584Y93829D01*
X2201204Y94079D01*
X2200887Y94496D01*
G01X2207127Y93579D02*
X2207000Y93663D01*
Y93829D01*
X2207127Y93913D01*
X2207254Y93829D01*
Y93663D01*
X2207127Y93579D01*
G01Y95829D02*
X2207000Y95913D01*
Y96079D01*
X2207127Y96163D01*
X2207254Y96079D01*
Y95913D01*
X2207127Y95829D01*
G01X2241624Y160276D02*
Y165276D01*
X2244030D01*
G01X2243144Y162859D02*
X2241624D01*
G01X2247927Y160276D02*
X2247547Y160359D01*
X2247167Y160693D01*
X2246914Y161276D01*
X2246787Y161943D01*
X2246914Y162609D01*
X2247167Y163193D01*
X2247547Y163526D01*
X2247927Y163609D01*
X2248307Y163526D01*
X2248687Y163193D01*
X2248940Y162609D01*
X2249004Y161943D01*
X2248940Y161276D01*
X2248687Y160693D01*
X2248307Y160359D01*
X2247927Y160276D01*
G01X2252140D02*
Y163609D01*
G01Y162943D02*
X2252457Y163276D01*
X2252774Y163526D01*
X2253217Y163609D01*
X2253534Y163526D01*
X2253914Y163276D01*
G01X2261960Y160276D02*
Y165276D01*
X2263480D01*
X2263987Y165026D01*
X2264367Y164443D01*
X2264494Y163776D01*
X2264367Y163109D01*
X2264050Y162609D01*
X2263480Y162359D01*
X2261960D01*
G01X2269467Y160276D02*
Y163609D01*
G01Y163026D02*
X2269214Y163359D01*
X2268834Y163526D01*
X2268390Y163609D01*
X2267947Y163443D01*
X2267567Y163109D01*
X2267314Y162609D01*
X2267187Y161943D01*
X2267314Y161276D01*
X2267567Y160776D01*
X2267947Y160443D01*
X2268390Y160276D01*
X2268834Y160359D01*
X2269214Y160609D01*
X2269467Y160943D01*
G01X2272350Y160276D02*
Y163609D01*
G01Y162776D02*
X2272604Y163193D01*
X2272984Y163526D01*
X2273490Y163609D01*
X2273934Y163526D01*
X2274314Y163193D01*
X2274504Y162609D01*
Y160276D01*
G01X2277577Y162526D02*
X2279604D01*
X2279414Y163109D01*
X2279097Y163443D01*
X2278654Y163609D01*
X2278210Y163526D01*
X2277830Y163276D01*
X2277577Y162693D01*
X2277450Y162193D01*
Y161693D01*
X2277577Y161193D01*
X2277894Y160693D01*
X2278274Y160359D01*
X2278717Y160276D01*
X2279160Y160443D01*
X2279604Y160943D01*
G01X2283627Y160276D02*
Y165276D01*
G01X2294334Y162943D02*
X2294587Y163193D01*
X2294777Y163609D01*
X2294904Y164193D01*
X2294777Y164693D01*
X2294524Y165026D01*
X2294080Y165276D01*
X2292370D01*
Y160276D01*
X2294460D01*
X2294904Y160609D01*
X2295157Y161109D01*
X2295284Y161693D01*
X2295157Y162276D01*
X2294777Y162776D01*
X2294334Y162943D01*
X2292370D01*
G01X2298927Y160276D02*
X2298547Y160359D01*
X2298167Y160693D01*
X2297914Y161276D01*
X2297787Y161943D01*
X2297914Y162609D01*
X2298167Y163193D01*
X2298547Y163526D01*
X2298927Y163609D01*
X2299307Y163526D01*
X2299687Y163193D01*
X2299940Y162609D01*
X2300004Y161943D01*
X2299940Y161276D01*
X2299687Y160693D01*
X2299307Y160359D01*
X2298927Y160276D01*
G01X2305167D02*
Y163609D01*
G01Y163026D02*
X2304914Y163359D01*
X2304534Y163526D01*
X2304090Y163609D01*
X2303647Y163443D01*
X2303267Y163109D01*
X2303014Y162609D01*
X2302887Y161943D01*
X2303014Y161276D01*
X2303267Y160776D01*
X2303647Y160443D01*
X2304090Y160276D01*
X2304534Y160359D01*
X2304914Y160609D01*
X2305167Y160943D01*
G01X2308240Y160276D02*
Y163609D01*
G01Y162943D02*
X2308557Y163276D01*
X2308874Y163526D01*
X2309317Y163609D01*
X2309634Y163526D01*
X2310014Y163276D01*
G01X2315367Y165276D02*
Y160276D01*
G01Y161026D02*
X2315114Y160609D01*
X2314734Y160359D01*
X2314290Y160276D01*
X2313784Y160443D01*
X2313404Y160859D01*
X2313150Y161359D01*
X2313087Y161943D01*
X2313150Y162526D01*
X2313404Y163026D01*
X2313784Y163443D01*
X2314290Y163609D01*
X2314734Y163526D01*
X2315050Y163359D01*
X2315367Y163026D01*
G01X2241624Y160276D02*
Y165276D01*
X2244030D01*
G01X2243144Y162859D02*
X2241624D01*
G01X2247927Y160276D02*
X2247547Y160359D01*
X2247167Y160693D01*
X2246914Y161276D01*
X2246787Y161943D01*
X2246914Y162609D01*
X2247167Y163193D01*
X2247547Y163526D01*
X2247927Y163609D01*
X2248307Y163526D01*
X2248687Y163193D01*
X2248940Y162609D01*
X2249004Y161943D01*
X2248940Y161276D01*
X2248687Y160693D01*
X2248307Y160359D01*
X2247927Y160276D01*
G01X2252140D02*
Y163609D01*
G01Y162943D02*
X2252457Y163276D01*
X2252774Y163526D01*
X2253217Y163609D01*
X2253534Y163526D01*
X2253914Y163276D01*
G01X2261960Y160276D02*
Y165276D01*
X2263480D01*
X2263987Y165026D01*
X2264367Y164443D01*
X2264494Y163776D01*
X2264367Y163109D01*
X2264050Y162609D01*
X2263480Y162359D01*
X2261960D01*
G01X2269467Y160276D02*
Y163609D01*
G01Y163026D02*
X2269214Y163359D01*
X2268834Y163526D01*
X2268390Y163609D01*
X2267947Y163443D01*
X2267567Y163109D01*
X2267314Y162609D01*
X2267187Y161943D01*
X2267314Y161276D01*
X2267567Y160776D01*
X2267947Y160443D01*
X2268390Y160276D01*
X2268834Y160359D01*
X2269214Y160609D01*
X2269467Y160943D01*
G01X2272350Y160276D02*
Y163609D01*
G01Y162776D02*
X2272604Y163193D01*
X2272984Y163526D01*
X2273490Y163609D01*
X2273934Y163526D01*
X2274314Y163193D01*
X2274504Y162609D01*
Y160276D01*
G01X2277577Y162526D02*
X2279604D01*
X2279414Y163109D01*
X2279097Y163443D01*
X2278654Y163609D01*
X2278210Y163526D01*
X2277830Y163276D01*
X2277577Y162693D01*
X2277450Y162193D01*
Y161693D01*
X2277577Y161193D01*
X2277894Y160693D01*
X2278274Y160359D01*
X2278717Y160276D01*
X2279160Y160443D01*
X2279604Y160943D01*
G01X2283627Y160276D02*
Y165276D01*
G01X2294334Y162943D02*
X2294587Y163193D01*
X2294777Y163609D01*
X2294904Y164193D01*
X2294777Y164693D01*
X2294524Y165026D01*
X2294080Y165276D01*
X2292370D01*
Y160276D01*
X2294460D01*
X2294904Y160609D01*
X2295157Y161109D01*
X2295284Y161693D01*
X2295157Y162276D01*
X2294777Y162776D01*
X2294334Y162943D01*
X2292370D01*
G01X2298927Y160276D02*
X2298547Y160359D01*
X2298167Y160693D01*
X2297914Y161276D01*
X2297787Y161943D01*
X2297914Y162609D01*
X2298167Y163193D01*
X2298547Y163526D01*
X2298927Y163609D01*
X2299307Y163526D01*
X2299687Y163193D01*
X2299940Y162609D01*
X2300004Y161943D01*
X2299940Y161276D01*
X2299687Y160693D01*
X2299307Y160359D01*
X2298927Y160276D01*
G01X2305167D02*
Y163609D01*
G01Y163026D02*
X2304914Y163359D01*
X2304534Y163526D01*
X2304090Y163609D01*
X2303647Y163443D01*
X2303267Y163109D01*
X2303014Y162609D01*
X2302887Y161943D01*
X2303014Y161276D01*
X2303267Y160776D01*
X2303647Y160443D01*
X2304090Y160276D01*
X2304534Y160359D01*
X2304914Y160609D01*
X2305167Y160943D01*
G01X2308240Y160276D02*
Y163609D01*
G01Y162943D02*
X2308557Y163276D01*
X2308874Y163526D01*
X2309317Y163609D01*
X2309634Y163526D01*
X2310014Y163276D01*
G01X2315367Y165276D02*
Y160276D01*
G01Y161026D02*
X2315114Y160609D01*
X2314734Y160359D01*
X2314290Y160276D01*
X2313784Y160443D01*
X2313404Y160859D01*
X2313150Y161359D01*
X2313087Y161943D01*
X2313150Y162526D01*
X2313404Y163026D01*
X2313784Y163443D01*
X2314290Y163609D01*
X2314734Y163526D01*
X2315050Y163359D01*
X2315367Y163026D01*
G01X2242827Y177876D02*
Y172876D01*
G01X2241370Y177876D02*
X2244284D01*
G01X2247927Y172876D02*
X2247547Y172959D01*
X2247167Y173293D01*
X2246914Y173876D01*
X2246787Y174543D01*
X2246914Y175209D01*
X2247167Y175793D01*
X2247547Y176126D01*
X2247927Y176209D01*
X2248307Y176126D01*
X2248687Y175793D01*
X2248940Y175209D01*
X2249004Y174543D01*
X2248940Y173876D01*
X2248687Y173293D01*
X2248307Y172959D01*
X2247927Y172876D01*
G01X2251887Y171209D02*
Y176209D01*
G01Y175459D02*
X2252204Y175876D01*
X2252520Y176126D01*
X2253027Y176209D01*
X2253470Y176126D01*
X2253914Y175709D01*
X2254104Y175126D01*
X2254167Y174543D01*
X2254104Y173959D01*
X2253914Y173376D01*
X2253534Y173043D01*
X2253027Y172876D01*
X2252584Y172959D01*
X2252140Y173209D01*
X2251887Y173543D01*
G01X2261644Y172876D02*
X2263227Y177876D01*
X2264810Y172876D01*
G01X2264240Y174626D02*
X2262214D01*
G01X2267250Y172876D02*
Y176209D01*
G01Y175376D02*
X2267504Y175793D01*
X2267884Y176126D01*
X2268390Y176209D01*
X2268834Y176126D01*
X2269214Y175793D01*
X2269404Y175209D01*
Y172876D01*
G01X2274567Y177876D02*
Y172876D01*
G01Y173626D02*
X2274314Y173209D01*
X2273934Y172959D01*
X2273490Y172876D01*
X2272984Y173043D01*
X2272604Y173459D01*
X2272350Y173959D01*
X2272287Y174543D01*
X2272350Y175126D01*
X2272604Y175626D01*
X2272984Y176043D01*
X2273490Y176209D01*
X2273934Y176126D01*
X2274250Y175959D01*
X2274567Y175626D01*
G01X2284134Y175543D02*
X2284387Y175793D01*
X2284577Y176209D01*
X2284704Y176793D01*
X2284577Y177293D01*
X2284324Y177626D01*
X2283880Y177876D01*
X2282170D01*
Y172876D01*
X2284260D01*
X2284704Y173209D01*
X2284957Y173709D01*
X2285084Y174293D01*
X2284957Y174876D01*
X2284577Y175376D01*
X2284134Y175543D01*
X2282170D01*
G01X2288727Y172876D02*
X2288347Y172959D01*
X2287967Y173293D01*
X2287714Y173876D01*
X2287587Y174543D01*
X2287714Y175209D01*
X2287967Y175793D01*
X2288347Y176126D01*
X2288727Y176209D01*
X2289107Y176126D01*
X2289487Y175793D01*
X2289740Y175209D01*
X2289804Y174543D01*
X2289740Y173876D01*
X2289487Y173293D01*
X2289107Y172959D01*
X2288727Y172876D01*
G01X2293827Y177876D02*
Y172876D01*
G01X2292940Y176209D02*
X2294714D01*
G01X2298927Y177876D02*
Y172876D01*
G01X2298040Y176209D02*
X2299814D01*
G01X2304027Y172876D02*
X2303647Y172959D01*
X2303267Y173293D01*
X2303014Y173876D01*
X2302887Y174543D01*
X2303014Y175209D01*
X2303267Y175793D01*
X2303647Y176126D01*
X2304027Y176209D01*
X2304407Y176126D01*
X2304787Y175793D01*
X2305040Y175209D01*
X2305104Y174543D01*
X2305040Y173876D01*
X2304787Y173293D01*
X2304407Y172959D01*
X2304027Y172876D01*
G01X2307227D02*
Y176209D01*
G01Y175293D02*
X2307417Y175709D01*
X2307734Y176043D01*
X2308177Y176209D01*
X2308620Y176043D01*
X2308937Y175709D01*
X2309127Y175293D01*
Y172876D01*
G01Y175293D02*
X2309317Y175709D01*
X2309634Y176043D01*
X2310077Y176209D01*
X2310520Y176043D01*
X2310837Y175709D01*
X2311027Y175209D01*
Y172876D01*
G01X2317997Y173543D02*
X2318504Y173126D01*
X2319074Y172876D01*
X2319580D01*
X2320087Y173126D01*
X2320467Y173543D01*
X2320657Y174126D01*
X2320530Y174709D01*
X2320214Y175209D01*
X2319644Y175543D01*
X2318884Y175709D01*
X2318440Y176043D01*
X2318250Y176626D01*
X2318377Y177209D01*
X2318694Y177626D01*
X2319137Y177876D01*
X2319580D01*
X2320024Y177709D01*
X2320404Y177293D01*
G01X2324427Y176209D02*
Y172876D01*
G01Y177543D02*
X2324300Y177626D01*
Y177793D01*
X2324427Y177876D01*
X2324554Y177793D01*
Y177626D01*
X2324427Y177543D01*
G01X2330667Y177876D02*
Y172876D01*
G01Y173626D02*
X2330414Y173209D01*
X2330034Y172959D01*
X2329590Y172876D01*
X2329084Y173043D01*
X2328704Y173459D01*
X2328450Y173959D01*
X2328387Y174543D01*
X2328450Y175126D01*
X2328704Y175626D01*
X2329084Y176043D01*
X2329590Y176209D01*
X2330034Y176126D01*
X2330350Y175959D01*
X2330667Y175626D01*
G01X2333677Y175126D02*
X2335704D01*
X2335514Y175709D01*
X2335197Y176043D01*
X2334754Y176209D01*
X2334310Y176126D01*
X2333930Y175876D01*
X2333677Y175293D01*
X2333550Y174793D01*
Y174293D01*
X2333677Y173793D01*
X2333994Y173293D01*
X2334374Y172959D01*
X2334817Y172876D01*
X2335260Y173043D01*
X2335704Y173543D01*
G01X2165124Y198076D02*
Y203076D01*
X2167530D01*
G01X2166644Y200659D02*
X2165124D01*
G01X2171427Y201409D02*
Y198076D01*
G01Y202743D02*
X2171300Y202826D01*
Y202993D01*
X2171427Y203076D01*
X2171554Y202993D01*
Y202826D01*
X2171427Y202743D01*
G01X2177667Y203076D02*
Y198076D01*
G01Y198826D02*
X2177414Y198409D01*
X2177034Y198159D01*
X2176590Y198076D01*
X2176084Y198243D01*
X2175704Y198659D01*
X2175450Y199159D01*
X2175387Y199743D01*
X2175450Y200326D01*
X2175704Y200826D01*
X2176084Y201243D01*
X2176590Y201409D01*
X2177034Y201326D01*
X2177350Y201159D01*
X2177667Y200826D01*
G01X2180550Y201409D02*
Y199076D01*
X2180804Y198493D01*
X2181184Y198159D01*
X2181627Y198076D01*
X2182070Y198159D01*
X2182450Y198493D01*
X2182704Y199076D01*
G01Y198076D02*
Y201409D01*
G01X2187740Y200993D02*
X2187297Y201326D01*
X2186917Y201409D01*
X2186410Y201243D01*
X2186030Y200909D01*
X2185777Y200326D01*
X2185714Y199743D01*
X2185777Y199159D01*
X2186030Y198659D01*
X2186410Y198243D01*
X2186917Y198076D01*
X2187360Y198243D01*
X2187740Y198576D01*
G01X2191827Y201409D02*
Y198076D01*
G01Y202743D02*
X2191700Y202826D01*
Y202993D01*
X2191827Y203076D01*
X2191954Y202993D01*
Y202826D01*
X2191827Y202743D01*
G01X2198067Y198076D02*
Y201409D01*
G01Y200826D02*
X2197814Y201159D01*
X2197434Y201326D01*
X2196990Y201409D01*
X2196547Y201243D01*
X2196167Y200909D01*
X2195914Y200409D01*
X2195787Y199743D01*
X2195914Y199076D01*
X2196167Y198576D01*
X2196547Y198243D01*
X2196990Y198076D01*
X2197434Y198159D01*
X2197814Y198409D01*
X2198067Y198743D01*
G01X2202027Y198076D02*
Y203076D01*
G01X2210580Y198076D02*
Y203076D01*
X2212227Y198909D01*
X2213874Y203076D01*
Y198076D01*
G01X2218467D02*
Y201409D01*
G01Y200826D02*
X2218214Y201159D01*
X2217834Y201326D01*
X2217390Y201409D01*
X2216947Y201243D01*
X2216567Y200909D01*
X2216314Y200409D01*
X2216187Y199743D01*
X2216314Y199076D01*
X2216567Y198576D01*
X2216947Y198243D01*
X2217390Y198076D01*
X2217834Y198159D01*
X2218214Y198409D01*
X2218467Y198743D01*
G01X2221540Y198076D02*
Y201409D01*
G01Y200743D02*
X2221857Y201076D01*
X2222174Y201326D01*
X2222617Y201409D01*
X2222934Y201326D01*
X2223314Y201076D01*
G01X2226450Y198076D02*
Y203076D01*
G01X2228477Y201409D02*
X2226450Y199493D01*
G01X2227274Y200243D02*
X2228604Y198076D01*
G01X2232627Y197909D02*
X2232500Y197993D01*
Y198159D01*
X2232627Y198243D01*
X2232754Y198159D01*
Y197993D01*
X2232627Y197909D01*
G01Y200159D02*
X2232500Y200243D01*
Y200409D01*
X2232627Y200493D01*
X2232754Y200409D01*
Y200243D01*
X2232627Y200159D01*
G01X2241434Y198076D02*
Y203076D01*
X2242700D01*
X2243207Y202826D01*
X2243587Y202493D01*
X2243904Y201993D01*
X2244157Y201409D01*
X2244220Y200576D01*
X2244157Y199743D01*
X2243904Y199159D01*
X2243587Y198659D01*
X2243207Y198326D01*
X2242700Y198076D01*
X2241434D01*
G01X2247927Y201409D02*
Y198076D01*
G01Y202743D02*
X2247800Y202826D01*
Y202993D01*
X2247927Y203076D01*
X2248054Y202993D01*
Y202826D01*
X2247927Y202743D01*
G01X2254167Y198076D02*
Y201409D01*
G01Y200826D02*
X2253914Y201159D01*
X2253534Y201326D01*
X2253090Y201409D01*
X2252647Y201243D01*
X2252267Y200909D01*
X2252014Y200409D01*
X2251887Y199743D01*
X2252014Y199076D01*
X2252267Y198576D01*
X2252647Y198243D01*
X2253090Y198076D01*
X2253534Y198159D01*
X2253914Y198409D01*
X2254167Y198743D01*
G01X2256227Y198076D02*
Y201409D01*
G01Y200493D02*
X2256417Y200909D01*
X2256734Y201243D01*
X2257177Y201409D01*
X2257620Y201243D01*
X2257937Y200909D01*
X2258127Y200493D01*
Y198076D01*
G01Y200493D02*
X2258317Y200909D01*
X2258634Y201243D01*
X2259077Y201409D01*
X2259520Y201243D01*
X2259837Y200909D01*
X2260027Y200409D01*
Y198076D01*
G01X2262277Y200326D02*
X2264304D01*
X2264114Y200909D01*
X2263797Y201243D01*
X2263354Y201409D01*
X2262910Y201326D01*
X2262530Y201076D01*
X2262277Y200493D01*
X2262150Y199993D01*
Y199493D01*
X2262277Y198993D01*
X2262594Y198493D01*
X2262974Y198159D01*
X2263417Y198076D01*
X2263860Y198243D01*
X2264304Y198743D01*
G01X2268327Y203076D02*
Y198076D01*
G01X2267440Y201409D02*
X2269214D01*
G01X2272477Y200326D02*
X2274504D01*
X2274314Y200909D01*
X2273997Y201243D01*
X2273554Y201409D01*
X2273110Y201326D01*
X2272730Y201076D01*
X2272477Y200493D01*
X2272350Y199993D01*
Y199493D01*
X2272477Y198993D01*
X2272794Y198493D01*
X2273174Y198159D01*
X2273617Y198076D01*
X2274060Y198243D01*
X2274504Y198743D01*
G01X2277640Y198076D02*
Y201409D01*
G01Y200743D02*
X2277957Y201076D01*
X2278274Y201326D01*
X2278717Y201409D01*
X2279034Y201326D01*
X2279414Y201076D01*
G01X2288727Y198076D02*
Y203076D01*
X2287967Y202076D01*
G01Y198076D02*
X2289487D01*
G01X2291927D02*
Y201409D01*
G01Y200493D02*
X2292117Y200909D01*
X2292434Y201243D01*
X2292877Y201409D01*
X2293320Y201243D01*
X2293637Y200909D01*
X2293827Y200493D01*
Y198076D01*
G01Y200493D02*
X2294017Y200909D01*
X2294334Y201243D01*
X2294777Y201409D01*
X2295220Y201243D01*
X2295537Y200909D01*
X2295727Y200409D01*
Y198076D01*
G01X2297027D02*
Y201409D01*
G01Y200493D02*
X2297217Y200909D01*
X2297534Y201243D01*
X2297977Y201409D01*
X2298420Y201243D01*
X2298737Y200909D01*
X2298927Y200493D01*
Y198076D01*
G01Y200493D02*
X2299117Y200909D01*
X2299434Y201243D01*
X2299877Y201409D01*
X2300320Y201243D01*
X2300637Y200909D01*
X2300827Y200409D01*
Y198076D01*
G01X2310520Y202659D02*
X2310140Y202909D01*
X2309697Y203076D01*
X2309190D01*
X2308620Y202826D01*
X2308177Y202409D01*
X2307860Y201909D01*
X2307607Y201076D01*
X2307544Y200326D01*
X2307670Y199576D01*
X2307860Y199076D01*
X2308240Y198576D01*
X2308684Y198243D01*
X2309127Y198076D01*
X2309570D01*
X2310014Y198243D01*
X2310394Y198493D01*
X2310710Y198826D01*
G01X2314227Y198076D02*
X2313847Y198159D01*
X2313467Y198493D01*
X2313214Y199076D01*
X2313087Y199743D01*
X2313214Y200409D01*
X2313467Y200993D01*
X2313847Y201326D01*
X2314227Y201409D01*
X2314607Y201326D01*
X2314987Y200993D01*
X2315240Y200409D01*
X2315304Y199743D01*
X2315240Y199076D01*
X2314987Y198493D01*
X2314607Y198159D01*
X2314227Y198076D01*
G01X2318187Y196409D02*
Y201409D01*
G01Y200659D02*
X2318504Y201076D01*
X2318820Y201326D01*
X2319327Y201409D01*
X2319770Y201326D01*
X2320214Y200909D01*
X2320404Y200326D01*
X2320467Y199743D01*
X2320404Y199159D01*
X2320214Y198576D01*
X2319834Y198243D01*
X2319327Y198076D01*
X2318884Y198159D01*
X2318440Y198409D01*
X2318187Y198743D01*
G01X2323287Y196409D02*
Y201409D01*
G01Y200659D02*
X2323604Y201076D01*
X2323920Y201326D01*
X2324427Y201409D01*
X2324870Y201326D01*
X2325314Y200909D01*
X2325504Y200326D01*
X2325567Y199743D01*
X2325504Y199159D01*
X2325314Y198576D01*
X2324934Y198243D01*
X2324427Y198076D01*
X2323984Y198159D01*
X2323540Y198409D01*
X2323287Y198743D01*
G01X2328577Y200326D02*
X2330604D01*
X2330414Y200909D01*
X2330097Y201243D01*
X2329654Y201409D01*
X2329210Y201326D01*
X2328830Y201076D01*
X2328577Y200493D01*
X2328450Y199993D01*
Y199493D01*
X2328577Y198993D01*
X2328894Y198493D01*
X2329274Y198159D01*
X2329717Y198076D01*
X2330160Y198243D01*
X2330604Y198743D01*
G01X2333740Y198076D02*
Y201409D01*
G01Y200743D02*
X2334057Y201076D01*
X2334374Y201326D01*
X2334817Y201409D01*
X2335134Y201326D01*
X2335514Y201076D01*
G01X2241434Y185476D02*
Y190476D01*
X2242700D01*
X2243207Y190226D01*
X2243587Y189893D01*
X2243904Y189393D01*
X2244157Y188809D01*
X2244220Y187976D01*
X2244157Y187143D01*
X2243904Y186559D01*
X2243587Y186059D01*
X2243207Y185726D01*
X2242700Y185476D01*
X2241434D01*
G01X2247927Y188809D02*
Y185476D01*
G01Y190143D02*
X2247800Y190226D01*
Y190393D01*
X2247927Y190476D01*
X2248054Y190393D01*
Y190226D01*
X2247927Y190143D01*
G01X2254167Y185476D02*
Y188809D01*
G01Y188226D02*
X2253914Y188559D01*
X2253534Y188726D01*
X2253090Y188809D01*
X2252647Y188643D01*
X2252267Y188309D01*
X2252014Y187809D01*
X2251887Y187143D01*
X2252014Y186476D01*
X2252267Y185976D01*
X2252647Y185643D01*
X2253090Y185476D01*
X2253534Y185559D01*
X2253914Y185809D01*
X2254167Y186143D01*
G01X2256227Y185476D02*
Y188809D01*
G01Y187893D02*
X2256417Y188309D01*
X2256734Y188643D01*
X2257177Y188809D01*
X2257620Y188643D01*
X2257937Y188309D01*
X2258127Y187893D01*
Y185476D01*
G01Y187893D02*
X2258317Y188309D01*
X2258634Y188643D01*
X2259077Y188809D01*
X2259520Y188643D01*
X2259837Y188309D01*
X2260027Y187809D01*
Y185476D01*
G01X2262277Y187726D02*
X2264304D01*
X2264114Y188309D01*
X2263797Y188643D01*
X2263354Y188809D01*
X2262910Y188726D01*
X2262530Y188476D01*
X2262277Y187893D01*
X2262150Y187393D01*
Y186893D01*
X2262277Y186393D01*
X2262594Y185893D01*
X2262974Y185559D01*
X2263417Y185476D01*
X2263860Y185643D01*
X2264304Y186143D01*
G01X2268327Y190476D02*
Y185476D01*
G01X2267440Y188809D02*
X2269214D01*
G01X2272477Y187726D02*
X2274504D01*
X2274314Y188309D01*
X2273997Y188643D01*
X2273554Y188809D01*
X2273110Y188726D01*
X2272730Y188476D01*
X2272477Y187893D01*
X2272350Y187393D01*
Y186893D01*
X2272477Y186393D01*
X2272794Y185893D01*
X2273174Y185559D01*
X2273617Y185476D01*
X2274060Y185643D01*
X2274504Y186143D01*
G01X2277640Y185476D02*
Y188809D01*
G01Y188143D02*
X2277957Y188476D01*
X2278274Y188726D01*
X2278717Y188809D01*
X2279034Y188726D01*
X2279414Y188476D01*
G01X2287334Y186476D02*
X2287714Y185893D01*
X2288220Y185559D01*
X2288790Y185476D01*
X2289297Y185559D01*
X2289804Y185976D01*
X2290120Y186476D01*
X2290184Y186976D01*
X2290057Y187559D01*
X2289614Y187976D01*
X2289170Y188143D01*
X2288600D01*
G01X2289170D02*
X2289550Y188393D01*
X2289867Y188809D01*
X2289994Y189309D01*
X2289867Y189809D01*
X2289550Y190226D01*
X2288980Y190476D01*
X2288410Y190393D01*
X2287840Y190059D01*
G01X2291927Y185476D02*
Y188809D01*
G01Y187893D02*
X2292117Y188309D01*
X2292434Y188643D01*
X2292877Y188809D01*
X2293320Y188643D01*
X2293637Y188309D01*
X2293827Y187893D01*
Y185476D01*
G01Y187893D02*
X2294017Y188309D01*
X2294334Y188643D01*
X2294777Y188809D01*
X2295220Y188643D01*
X2295537Y188309D01*
X2295727Y187809D01*
Y185476D01*
G01X2297027D02*
Y188809D01*
G01Y187893D02*
X2297217Y188309D01*
X2297534Y188643D01*
X2297977Y188809D01*
X2298420Y188643D01*
X2298737Y188309D01*
X2298927Y187893D01*
Y185476D01*
G01Y187893D02*
X2299117Y188309D01*
X2299434Y188643D01*
X2299877Y188809D01*
X2300320Y188643D01*
X2300637Y188309D01*
X2300827Y187809D01*
Y185476D01*
G01X2307797Y186143D02*
X2308304Y185726D01*
X2308874Y185476D01*
X2309380D01*
X2309887Y185726D01*
X2310267Y186143D01*
X2310457Y186726D01*
X2310330Y187309D01*
X2310014Y187809D01*
X2309444Y188143D01*
X2308684Y188309D01*
X2308240Y188643D01*
X2308050Y189226D01*
X2308177Y189809D01*
X2308494Y190226D01*
X2308937Y190476D01*
X2309380D01*
X2309824Y190309D01*
X2310204Y189893D01*
G01X2314227Y185476D02*
X2313847Y185559D01*
X2313467Y185893D01*
X2313214Y186476D01*
X2313087Y187143D01*
X2313214Y187809D01*
X2313467Y188393D01*
X2313847Y188726D01*
X2314227Y188809D01*
X2314607Y188726D01*
X2314987Y188393D01*
X2315240Y187809D01*
X2315304Y187143D01*
X2315240Y186476D01*
X2314987Y185893D01*
X2314607Y185559D01*
X2314227Y185476D01*
G01X2319327D02*
Y190476D01*
G01X2325567D02*
Y185476D01*
G01Y186226D02*
X2325314Y185809D01*
X2324934Y185559D01*
X2324490Y185476D01*
X2323984Y185643D01*
X2323604Y186059D01*
X2323350Y186559D01*
X2323287Y187143D01*
X2323350Y187726D01*
X2323604Y188226D01*
X2323984Y188643D01*
X2324490Y188809D01*
X2324934Y188726D01*
X2325250Y188559D01*
X2325567Y188226D01*
G01X2328577Y187726D02*
X2330604D01*
X2330414Y188309D01*
X2330097Y188643D01*
X2329654Y188809D01*
X2329210Y188726D01*
X2328830Y188476D01*
X2328577Y187893D01*
X2328450Y187393D01*
Y186893D01*
X2328577Y186393D01*
X2328894Y185893D01*
X2329274Y185559D01*
X2329717Y185476D01*
X2330160Y185643D01*
X2330604Y186143D01*
G01X2333740Y185476D02*
Y188809D01*
G01Y188143D02*
X2334057Y188476D01*
X2334374Y188726D01*
X2334817Y188809D01*
X2335134Y188726D01*
X2335514Y188476D01*
G01X2337827Y185476D02*
Y188809D01*
G01Y187893D02*
X2338017Y188309D01*
X2338334Y188643D01*
X2338777Y188809D01*
X2339220Y188643D01*
X2339537Y188309D01*
X2339727Y187893D01*
Y185476D01*
G01Y187893D02*
X2339917Y188309D01*
X2340234Y188643D01*
X2340677Y188809D01*
X2341120Y188643D01*
X2341437Y188309D01*
X2341627Y187809D01*
Y185476D01*
G01X2345967D02*
Y188809D01*
G01Y188226D02*
X2345714Y188559D01*
X2345334Y188726D01*
X2344890Y188809D01*
X2344447Y188643D01*
X2344067Y188309D01*
X2343814Y187809D01*
X2343687Y187143D01*
X2343814Y186476D01*
X2344067Y185976D01*
X2344447Y185643D01*
X2344890Y185476D01*
X2345334Y185559D01*
X2345714Y185809D01*
X2345967Y186143D01*
G01X2348977Y186059D02*
X2349294Y185726D01*
X2349737Y185476D01*
X2350117D01*
X2350497Y185643D01*
X2350750Y185893D01*
X2350877Y186226D01*
X2350814Y186726D01*
X2350560Y186976D01*
X2349420Y187476D01*
X2349167Y188059D01*
X2349294Y188476D01*
X2349547Y188726D01*
X2349927Y188809D01*
X2350307Y188726D01*
X2350687Y188476D01*
G01X2353950Y185476D02*
Y190476D01*
G01X2355977Y188809D02*
X2353950Y186893D01*
G01X2354774Y187643D02*
X2356104Y185476D01*
G01X2238515Y259768D02*
Y254768D01*
G01X2237058Y259768D02*
X2239972D01*
G01X2243615Y254768D02*
X2243235Y254851D01*
X2242855Y255185D01*
X2242602Y255768D01*
X2242475Y256435D01*
X2242602Y257101D01*
X2242855Y257685D01*
X2243235Y258018D01*
X2243615Y258101D01*
X2243995Y258018D01*
X2244375Y257685D01*
X2244628Y257101D01*
X2244692Y256435D01*
X2244628Y255768D01*
X2244375Y255185D01*
X2243995Y254851D01*
X2243615Y254768D01*
G01X2248715D02*
Y259768D01*
G01X2252865Y257018D02*
X2254892D01*
X2254702Y257601D01*
X2254385Y257935D01*
X2253942Y258101D01*
X2253498Y258018D01*
X2253118Y257768D01*
X2252865Y257185D01*
X2252738Y256685D01*
Y256185D01*
X2252865Y255685D01*
X2253182Y255185D01*
X2253562Y254851D01*
X2254005Y254768D01*
X2254448Y254935D01*
X2254892Y255435D01*
G01X2258028Y254768D02*
Y258101D01*
G01Y257435D02*
X2258345Y257768D01*
X2258662Y258018D01*
X2259105Y258101D01*
X2259422Y258018D01*
X2259802Y257768D01*
G01X2265155Y254768D02*
Y258101D01*
G01Y257518D02*
X2264902Y257851D01*
X2264522Y258018D01*
X2264078Y258101D01*
X2263635Y257935D01*
X2263255Y257601D01*
X2263002Y257101D01*
X2262875Y256435D01*
X2263002Y255768D01*
X2263255Y255268D01*
X2263635Y254935D01*
X2264078Y254768D01*
X2264522Y254851D01*
X2264902Y255101D01*
X2265155Y255435D01*
G01X2268038Y254768D02*
Y258101D01*
G01Y257268D02*
X2268292Y257685D01*
X2268672Y258018D01*
X2269178Y258101D01*
X2269622Y258018D01*
X2270002Y257685D01*
X2270192Y257101D01*
Y254768D01*
G01X2275228Y257685D02*
X2274785Y258018D01*
X2274405Y258101D01*
X2273898Y257935D01*
X2273518Y257601D01*
X2273265Y257018D01*
X2273202Y256435D01*
X2273265Y255851D01*
X2273518Y255351D01*
X2273898Y254935D01*
X2274405Y254768D01*
X2274848Y254935D01*
X2275228Y255268D01*
G01X2278365Y257018D02*
X2280392D01*
X2280202Y257601D01*
X2279885Y257935D01*
X2279442Y258101D01*
X2278998Y258018D01*
X2278618Y257768D01*
X2278365Y257185D01*
X2278238Y256685D01*
Y256185D01*
X2278365Y255685D01*
X2278682Y255185D01*
X2279062Y254851D01*
X2279505Y254768D01*
X2279948Y254935D01*
X2280392Y255435D01*
G01X2288818Y256435D02*
X2290338D01*
G01X2289515Y257518D02*
Y255351D01*
G01X2294615Y259768D02*
X2294108Y259601D01*
X2293728Y259185D01*
X2293475Y258685D01*
X2293285Y258018D01*
X2293222Y257268D01*
X2293285Y256518D01*
X2293475Y255851D01*
X2293728Y255351D01*
X2294108Y254935D01*
X2294615Y254768D01*
X2295122Y254935D01*
X2295502Y255351D01*
X2295755Y255851D01*
X2295945Y256518D01*
X2296008Y257268D01*
X2295945Y258018D01*
X2295755Y258685D01*
X2295502Y259185D01*
X2295122Y259601D01*
X2294615Y259768D01*
G01X2299715Y254601D02*
X2299588Y254685D01*
Y254851D01*
X2299715Y254935D01*
X2299842Y254851D01*
Y254685D01*
X2299715Y254601D01*
G01X2304815Y259768D02*
X2304308Y259601D01*
X2303928Y259185D01*
X2303675Y258685D01*
X2303485Y258018D01*
X2303422Y257268D01*
X2303485Y256518D01*
X2303675Y255851D01*
X2303928Y255351D01*
X2304308Y254935D01*
X2304815Y254768D01*
X2305322Y254935D01*
X2305702Y255351D01*
X2305955Y255851D01*
X2306145Y256518D01*
X2306208Y257268D01*
X2306145Y258018D01*
X2305955Y258685D01*
X2305702Y259185D01*
X2305322Y259601D01*
X2304815Y259768D01*
G01X2308522Y255518D02*
X2308902Y255101D01*
X2309345Y254851D01*
X2309915Y254768D01*
X2310485Y254935D01*
X2310928Y255268D01*
X2311245Y255851D01*
X2311308Y256518D01*
X2311182Y257185D01*
X2310865Y257601D01*
X2310422Y257935D01*
X2309978Y258018D01*
X2309535Y257935D01*
X2308965Y257601D01*
X2309155Y259768D01*
X2310865D01*
G01X2315015D02*
X2314508Y259601D01*
X2314128Y259185D01*
X2313875Y258685D01*
X2313685Y258018D01*
X2313622Y257268D01*
X2313685Y256518D01*
X2313875Y255851D01*
X2314128Y255351D01*
X2314508Y254935D01*
X2315015Y254768D01*
X2315522Y254935D01*
X2315902Y255351D01*
X2316155Y255851D01*
X2316345Y256518D01*
X2316408Y257268D01*
X2316345Y258018D01*
X2316155Y258685D01*
X2315902Y259185D01*
X2315522Y259601D01*
X2315015Y259768D01*
G01X2320115Y254768D02*
X2320558Y254851D01*
X2321065Y255101D01*
X2321382Y255518D01*
X2321508Y256101D01*
X2321382Y256685D01*
X2321002Y257185D01*
X2320432Y257435D01*
X2319798D01*
X2319418Y257601D01*
X2319102Y258018D01*
X2318975Y258601D01*
X2319165Y259185D01*
X2319608Y259601D01*
X2320115Y259768D01*
X2320622Y259601D01*
X2321065Y259185D01*
X2321255Y258601D01*
X2321128Y258018D01*
X2320812Y257601D01*
X2320432Y257435D01*
X2319798D01*
X2319228Y257185D01*
X2318848Y256685D01*
X2318722Y256101D01*
X2318848Y255518D01*
X2319165Y255101D01*
X2319672Y254851D01*
X2320115Y254768D01*
G01X2323315D02*
Y258101D01*
G01Y257185D02*
X2323505Y257601D01*
X2323822Y257935D01*
X2324265Y258101D01*
X2324708Y257935D01*
X2325025Y257601D01*
X2325215Y257185D01*
Y254768D01*
G01Y257185D02*
X2325405Y257601D01*
X2325722Y257935D01*
X2326165Y258101D01*
X2326608Y257935D01*
X2326925Y257601D01*
X2327115Y257101D01*
Y254768D01*
G01X2328415D02*
Y258101D01*
G01Y257185D02*
X2328605Y257601D01*
X2328922Y257935D01*
X2329365Y258101D01*
X2329808Y257935D01*
X2330125Y257601D01*
X2330315Y257185D01*
Y254768D01*
G01Y257185D02*
X2330505Y257601D01*
X2330822Y257935D01*
X2331265Y258101D01*
X2331708Y257935D01*
X2332025Y257601D01*
X2332215Y257101D01*
Y254768D01*
G01X2334275Y254601D02*
X2336555Y259768D01*
G01X2339692Y256435D02*
X2341338D01*
G01X2345615Y259768D02*
X2345108Y259601D01*
X2344728Y259185D01*
X2344475Y258685D01*
X2344285Y258018D01*
X2344222Y257268D01*
X2344285Y256518D01*
X2344475Y255851D01*
X2344728Y255351D01*
X2345108Y254935D01*
X2345615Y254768D01*
X2346122Y254935D01*
X2346502Y255351D01*
X2346755Y255851D01*
X2346945Y256518D01*
X2347008Y257268D01*
X2346945Y258018D01*
X2346755Y258685D01*
X2346502Y259185D01*
X2346122Y259601D01*
X2345615Y259768D01*
G01X2350715Y254601D02*
X2350588Y254685D01*
Y254851D01*
X2350715Y254935D01*
X2350842Y254851D01*
Y254685D01*
X2350715Y254601D01*
G01X2355815Y259768D02*
X2355308Y259601D01*
X2354928Y259185D01*
X2354675Y258685D01*
X2354485Y258018D01*
X2354422Y257268D01*
X2354485Y256518D01*
X2354675Y255851D01*
X2354928Y255351D01*
X2355308Y254935D01*
X2355815Y254768D01*
X2356322Y254935D01*
X2356702Y255351D01*
X2356955Y255851D01*
X2357145Y256518D01*
X2357208Y257268D01*
X2357145Y258018D01*
X2356955Y258685D01*
X2356702Y259185D01*
X2356322Y259601D01*
X2355815Y259768D01*
G01X2360915D02*
X2360408Y259601D01*
X2360028Y259185D01*
X2359775Y258685D01*
X2359585Y258018D01*
X2359522Y257268D01*
X2359585Y256518D01*
X2359775Y255851D01*
X2360028Y255351D01*
X2360408Y254935D01*
X2360915Y254768D01*
X2361422Y254935D01*
X2361802Y255351D01*
X2362055Y255851D01*
X2362245Y256518D01*
X2362308Y257268D01*
X2362245Y258018D01*
X2362055Y258685D01*
X2361802Y259185D01*
X2361422Y259601D01*
X2360915Y259768D01*
G01X2366015D02*
X2365508Y259601D01*
X2365128Y259185D01*
X2364875Y258685D01*
X2364685Y258018D01*
X2364622Y257268D01*
X2364685Y256518D01*
X2364875Y255851D01*
X2365128Y255351D01*
X2365508Y254935D01*
X2366015Y254768D01*
X2366522Y254935D01*
X2366902Y255351D01*
X2367155Y255851D01*
X2367345Y256518D01*
X2367408Y257268D01*
X2367345Y258018D01*
X2367155Y258685D01*
X2366902Y259185D01*
X2366522Y259601D01*
X2366015Y259768D01*
G01X2371115D02*
X2370608Y259601D01*
X2370228Y259185D01*
X2369975Y258685D01*
X2369785Y258018D01*
X2369722Y257268D01*
X2369785Y256518D01*
X2369975Y255851D01*
X2370228Y255351D01*
X2370608Y254935D01*
X2371115Y254768D01*
X2371622Y254935D01*
X2372002Y255351D01*
X2372255Y255851D01*
X2372445Y256518D01*
X2372508Y257268D01*
X2372445Y258018D01*
X2372255Y258685D01*
X2372002Y259185D01*
X2371622Y259601D01*
X2371115Y259768D01*
G01X2374315Y254768D02*
Y258101D01*
G01Y257185D02*
X2374505Y257601D01*
X2374822Y257935D01*
X2375265Y258101D01*
X2375708Y257935D01*
X2376025Y257601D01*
X2376215Y257185D01*
Y254768D01*
G01Y257185D02*
X2376405Y257601D01*
X2376722Y257935D01*
X2377165Y258101D01*
X2377608Y257935D01*
X2377925Y257601D01*
X2378115Y257101D01*
Y254768D01*
G01X2379415D02*
Y258101D01*
G01Y257185D02*
X2379605Y257601D01*
X2379922Y257935D01*
X2380365Y258101D01*
X2380808Y257935D01*
X2381125Y257601D01*
X2381315Y257185D01*
Y254768D01*
G01Y257185D02*
X2381505Y257601D01*
X2381822Y257935D01*
X2382265Y258101D01*
X2382708Y257935D01*
X2383025Y257601D01*
X2383215Y257101D01*
Y254768D01*
G01X2167115Y272368D02*
Y267368D01*
G01X2165658Y272368D02*
X2168572D01*
G01X2172215Y267368D02*
X2171835Y267451D01*
X2171455Y267785D01*
X2171202Y268368D01*
X2171075Y269035D01*
X2171202Y269701D01*
X2171455Y270285D01*
X2171835Y270618D01*
X2172215Y270701D01*
X2172595Y270618D01*
X2172975Y270285D01*
X2173228Y269701D01*
X2173292Y269035D01*
X2173228Y268368D01*
X2172975Y267785D01*
X2172595Y267451D01*
X2172215Y267368D01*
G01X2177315D02*
X2176935Y267451D01*
X2176555Y267785D01*
X2176302Y268368D01*
X2176175Y269035D01*
X2176302Y269701D01*
X2176555Y270285D01*
X2176935Y270618D01*
X2177315Y270701D01*
X2177695Y270618D01*
X2178075Y270285D01*
X2178328Y269701D01*
X2178392Y269035D01*
X2178328Y268368D01*
X2178075Y267785D01*
X2177695Y267451D01*
X2177315Y267368D01*
G01X2182415D02*
Y272368D01*
G01X2187515Y270701D02*
Y267368D01*
G01Y272035D02*
X2187388Y272118D01*
Y272285D01*
X2187515Y272368D01*
X2187642Y272285D01*
Y272118D01*
X2187515Y272035D01*
G01X2191538Y267368D02*
Y270701D01*
G01Y269868D02*
X2191792Y270285D01*
X2192172Y270618D01*
X2192678Y270701D01*
X2193122Y270618D01*
X2193502Y270285D01*
X2193692Y269701D01*
Y267368D01*
G01X2196828Y266118D02*
X2197272Y265785D01*
X2197778Y265701D01*
X2198222Y265785D01*
X2198602Y266201D01*
X2198855Y266785D01*
Y270701D01*
G01Y270035D02*
X2198602Y270368D01*
X2198222Y270618D01*
X2197778Y270701D01*
X2197272Y270535D01*
X2196955Y270201D01*
X2196702Y269618D01*
X2196575Y269035D01*
X2196638Y268535D01*
X2196892Y267951D01*
X2197272Y267535D01*
X2197778Y267368D01*
X2198158Y267451D01*
X2198602Y267785D01*
X2198855Y268118D01*
G01X2206585Y267368D02*
Y272368D01*
G01X2209245D02*
Y267368D01*
G01Y269868D02*
X2206585D01*
G01X2213015Y267368D02*
X2212635Y267451D01*
X2212255Y267785D01*
X2212002Y268368D01*
X2211875Y269035D01*
X2212002Y269701D01*
X2212255Y270285D01*
X2212635Y270618D01*
X2213015Y270701D01*
X2213395Y270618D01*
X2213775Y270285D01*
X2214028Y269701D01*
X2214092Y269035D01*
X2214028Y268368D01*
X2213775Y267785D01*
X2213395Y267451D01*
X2213015Y267368D01*
G01X2218115D02*
Y272368D01*
G01X2222265Y269618D02*
X2224292D01*
X2224102Y270201D01*
X2223785Y270535D01*
X2223342Y270701D01*
X2222898Y270618D01*
X2222518Y270368D01*
X2222265Y269785D01*
X2222138Y269285D01*
Y268785D01*
X2222265Y268285D01*
X2222582Y267785D01*
X2222962Y267451D01*
X2223405Y267368D01*
X2223848Y267535D01*
X2224292Y268035D01*
G01X2228315Y267201D02*
X2228188Y267285D01*
Y267451D01*
X2228315Y267535D01*
X2228442Y267451D01*
Y267285D01*
X2228315Y267201D01*
G01Y269451D02*
X2228188Y269535D01*
Y269701D01*
X2228315Y269785D01*
X2228442Y269701D01*
Y269535D01*
X2228315Y269451D01*
G01X2237122Y267368D02*
Y272368D01*
X2238388D01*
X2238895Y272118D01*
X2239275Y271785D01*
X2239592Y271285D01*
X2239845Y270701D01*
X2239908Y269868D01*
X2239845Y269035D01*
X2239592Y268451D01*
X2239275Y267951D01*
X2238895Y267618D01*
X2238388Y267368D01*
X2237122D01*
G01X2243615Y270701D02*
Y267368D01*
G01Y272035D02*
X2243488Y272118D01*
Y272285D01*
X2243615Y272368D01*
X2243742Y272285D01*
Y272118D01*
X2243615Y272035D01*
G01X2249855Y267368D02*
Y270701D01*
G01Y270118D02*
X2249602Y270451D01*
X2249222Y270618D01*
X2248778Y270701D01*
X2248335Y270535D01*
X2247955Y270201D01*
X2247702Y269701D01*
X2247575Y269035D01*
X2247702Y268368D01*
X2247955Y267868D01*
X2248335Y267535D01*
X2248778Y267368D01*
X2249222Y267451D01*
X2249602Y267701D01*
X2249855Y268035D01*
G01X2251915Y267368D02*
Y270701D01*
G01Y269785D02*
X2252105Y270201D01*
X2252422Y270535D01*
X2252865Y270701D01*
X2253308Y270535D01*
X2253625Y270201D01*
X2253815Y269785D01*
Y267368D01*
G01Y269785D02*
X2254005Y270201D01*
X2254322Y270535D01*
X2254765Y270701D01*
X2255208Y270535D01*
X2255525Y270201D01*
X2255715Y269701D01*
Y267368D01*
G01X2257965Y269618D02*
X2259992D01*
X2259802Y270201D01*
X2259485Y270535D01*
X2259042Y270701D01*
X2258598Y270618D01*
X2258218Y270368D01*
X2257965Y269785D01*
X2257838Y269285D01*
Y268785D01*
X2257965Y268285D01*
X2258282Y267785D01*
X2258662Y267451D01*
X2259105Y267368D01*
X2259548Y267535D01*
X2259992Y268035D01*
G01X2264015Y272368D02*
Y267368D01*
G01X2263128Y270701D02*
X2264902D01*
G01X2268165Y269618D02*
X2270192D01*
X2270002Y270201D01*
X2269685Y270535D01*
X2269242Y270701D01*
X2268798Y270618D01*
X2268418Y270368D01*
X2268165Y269785D01*
X2268038Y269285D01*
Y268785D01*
X2268165Y268285D01*
X2268482Y267785D01*
X2268862Y267451D01*
X2269305Y267368D01*
X2269748Y267535D01*
X2270192Y268035D01*
G01X2273328Y267368D02*
Y270701D01*
G01Y270035D02*
X2273645Y270368D01*
X2273962Y270618D01*
X2274405Y270701D01*
X2274722Y270618D01*
X2275102Y270368D01*
G01X2283022Y268368D02*
X2283402Y267785D01*
X2283908Y267451D01*
X2284478Y267368D01*
X2284985Y267451D01*
X2285492Y267868D01*
X2285808Y268368D01*
X2285872Y268868D01*
X2285745Y269451D01*
X2285302Y269868D01*
X2284858Y270035D01*
X2284288D01*
G01X2284858D02*
X2285238Y270285D01*
X2285555Y270701D01*
X2285682Y271201D01*
X2285555Y271701D01*
X2285238Y272118D01*
X2284668Y272368D01*
X2284098Y272285D01*
X2283528Y271951D01*
G01X2289515Y267201D02*
X2289388Y267285D01*
Y267451D01*
X2289515Y267535D01*
X2289642Y267451D01*
Y267285D01*
X2289515Y267201D01*
G01X2294615Y267368D02*
Y272368D01*
X2293855Y271368D01*
G01Y267368D02*
X2295375D01*
G01X2299588D02*
X2299715Y268451D01*
X2299905Y269368D01*
X2300158Y270201D01*
X2300475Y271118D01*
X2300982Y272368D01*
X2298448D01*
G01X2303422Y268118D02*
X2303802Y267701D01*
X2304245Y267451D01*
X2304815Y267368D01*
X2305385Y267535D01*
X2305828Y267868D01*
X2306145Y268451D01*
X2306208Y269118D01*
X2306082Y269785D01*
X2305765Y270201D01*
X2305322Y270535D01*
X2304878Y270618D01*
X2304435Y270535D01*
X2303865Y270201D01*
X2304055Y272368D01*
X2305765D01*
G01X2308015Y267368D02*
Y270701D01*
G01Y269785D02*
X2308205Y270201D01*
X2308522Y270535D01*
X2308965Y270701D01*
X2309408Y270535D01*
X2309725Y270201D01*
X2309915Y269785D01*
Y267368D01*
G01Y269785D02*
X2310105Y270201D01*
X2310422Y270535D01*
X2310865Y270701D01*
X2311308Y270535D01*
X2311625Y270201D01*
X2311815Y269701D01*
Y267368D01*
G01X2313115D02*
Y270701D01*
G01Y269785D02*
X2313305Y270201D01*
X2313622Y270535D01*
X2314065Y270701D01*
X2314508Y270535D01*
X2314825Y270201D01*
X2315015Y269785D01*
Y267368D01*
G01Y269785D02*
X2315205Y270201D01*
X2315522Y270535D01*
X2315965Y270701D01*
X2316408Y270535D01*
X2316725Y270201D01*
X2316915Y269701D01*
Y267368D01*
G01X2323758D02*
Y272368D01*
X2326672Y267368D01*
Y272368D01*
G01X2329048Y267368D02*
Y272368D01*
X2330568D01*
X2331075Y272118D01*
X2331455Y271535D01*
X2331582Y270868D01*
X2331455Y270201D01*
X2331138Y269701D01*
X2330568Y269451D01*
X2329048D01*
G01X2335415Y272368D02*
Y267368D01*
G01X2333958Y272368D02*
X2336872D01*
G01X2339185Y267368D02*
Y272368D01*
G01X2341845D02*
Y267368D01*
G01Y269868D02*
X2339185D01*
G01X2193522Y48076D02*
X2192538Y53982D01*
X2191553Y48076D01*
X2193522D01*
G01X2185871Y56716D02*
X2185371Y57096D01*
X2185121Y57539D01*
X2185038Y58046D01*
X2185205Y58679D01*
X2185621Y59122D01*
X2186121Y59249D01*
X2186621Y59186D01*
X2187038Y58932D01*
X2187871Y57666D01*
X2188455Y57096D01*
X2189288Y56716D01*
X2190038Y56589D01*
Y59249D01*
G01X2191553Y67761D02*
X2192538Y61856D01*
X2193522Y67761D01*
X2191553D01*
G01X2192538Y57919D02*
Y61856D01*
G01Y57919D02*
Y53982D01*
G01X2207105D02*
X2192144D01*
G01X2207105Y61856D02*
X2192144D01*
G01X2194368Y134596D02*
X2207831Y113055D01*
G01X2198333Y130110D02*
X2194368Y134596D01*
X2196664Y129067D01*
X2198333Y130110D01*
G01X2206957Y119171D02*
X2211197Y121821D01*
X2209946Y121935D01*
G01X2206554Y119815D02*
X2207360Y118526D01*
G01X2210561Y125197D02*
X2201551Y125462D01*
G01X2208556Y125330D02*
G03I-2500J0D01*
G01X2199917Y137151D02*
X2230246Y144150D01*
G01X2205450Y139438D02*
X2199917Y137151D01*
X2205893Y137520D01*
X2205450Y139438D01*
G01X2199663Y234938D02*
X2243766Y244703D01*
G01X2205217Y237176D02*
X2199663Y234938D01*
X2205642Y235254D01*
X2205217Y237176D01*
G01X2213316Y246923D02*
X2210055Y238520D01*
G01X2214185Y242721D02*
G03I-2500J0D01*
G01X2215766Y35281D02*
X2221671Y36265D01*
X2215766Y37250D01*
Y35281D01*
G01X2226578Y39765D02*
X2226958Y39182D01*
X2227464Y38848D01*
X2228034Y38765D01*
X2228541Y38848D01*
X2229048Y39265D01*
X2229364Y39765D01*
X2229428Y40265D01*
X2229301Y40848D01*
X2228858Y41265D01*
X2228414Y41432D01*
X2227844D01*
G01X2228414D02*
X2228794Y41682D01*
X2229111Y42098D01*
X2229238Y42598D01*
X2229111Y43098D01*
X2228794Y43515D01*
X2228224Y43765D01*
X2227654Y43682D01*
X2227084Y43348D01*
G01X2227971Y36265D02*
X2233482D01*
G01X2227971D02*
X2221671D01*
G01Y55557D02*
Y35872D01*
G01X2222596Y145976D02*
X2223097Y145493D01*
X2223666Y145282D01*
X2224240Y145329D01*
X2224715Y145525D01*
X2225115Y146044D01*
X2225311Y146603D01*
X2225260Y147104D01*
X2225006Y147644D01*
X2224480Y147950D01*
X2224011Y148013D01*
X2223455Y147885D01*
G01X2224011Y148013D02*
X2224325Y148342D01*
X2224540Y148819D01*
X2224551Y149335D01*
X2224315Y149794D01*
X2223913Y150129D01*
X2223301Y150244D01*
X2222764Y150035D01*
X2222284Y149582D01*
G01X2219655Y150685D02*
X2216470Y142254D01*
G01X2220563Y146469D02*
G03I-2501J0D01*
G01X2216215Y242188D02*
X2216712Y241700D01*
X2217278Y241485D01*
X2217853Y241526D01*
X2218330Y241717D01*
X2218734Y242234D01*
X2218935Y242790D01*
X2218889Y243292D01*
X2218639Y243834D01*
X2218116Y244145D01*
X2217647Y244212D01*
X2217091Y244089D01*
G01X2217647Y244212D02*
X2217964Y244538D01*
X2218184Y245014D01*
X2218199Y245529D01*
X2217967Y245990D01*
X2217568Y246328D01*
X2216958Y246449D01*
X2216419Y246245D01*
X2215935Y245796D01*
G01X2222806Y242452D02*
X2222664Y242506D01*
X2222628Y242669D01*
X2222734Y242777D01*
X2222876Y242723D01*
X2222912Y242561D01*
X2222806Y242452D01*
G01X2227749Y243717D02*
X2226668Y248598D01*
X2226142Y247458D01*
G01X2227007Y243552D02*
X2228491Y243881D01*
G01X2232604Y244791D02*
X2232494Y245876D01*
X2232481Y246812D01*
X2232548Y247681D01*
X2232660Y248644D01*
X2232884Y249974D01*
X2230411Y249427D01*
G01X2236185Y246352D02*
X2236646Y246027D01*
X2237132Y245879D01*
X2237707Y245921D01*
X2238228Y246207D01*
X2238588Y246628D01*
X2238771Y247266D01*
X2238689Y247930D01*
X2238421Y248554D01*
X2238022Y248892D01*
X2237517Y249122D01*
X2237066Y249107D01*
X2236652Y248930D01*
X2236167Y248482D01*
X2235884Y250638D01*
X2237554Y251008D01*
G01X2239388Y37250D02*
X2233482Y36265D01*
X2239388Y35281D01*
Y37250D01*
G01X2233482Y55557D02*
Y35872D01*
G01X2341989Y-8223D02*
Y-3223D01*
X2343509D01*
X2344016Y-3473D01*
X2344396Y-4056D01*
X2344523Y-4723D01*
X2344396Y-5390D01*
X2344079Y-5890D01*
X2343509Y-6140D01*
X2341989D01*
G01X2349496Y-8223D02*
Y-4890D01*
G01Y-5473D02*
X2349243Y-5140D01*
X2348863Y-4973D01*
X2348419Y-4890D01*
X2347976Y-5056D01*
X2347596Y-5390D01*
X2347343Y-5890D01*
X2347216Y-6556D01*
X2347343Y-7223D01*
X2347596Y-7723D01*
X2347976Y-8056D01*
X2348419Y-8223D01*
X2348863Y-8140D01*
X2349243Y-7890D01*
X2349496Y-7556D01*
G01X2352379Y-8223D02*
Y-4890D01*
G01Y-5723D02*
X2352633Y-5306D01*
X2353013Y-4973D01*
X2353519Y-4890D01*
X2353963Y-4973D01*
X2354343Y-5306D01*
X2354533Y-5890D01*
Y-8223D01*
G01X2357606Y-5973D02*
X2359633D01*
X2359443Y-5390D01*
X2359126Y-5056D01*
X2358683Y-4890D01*
X2358239Y-4973D01*
X2357859Y-5223D01*
X2357606Y-5806D01*
X2357479Y-6306D01*
Y-6806D01*
X2357606Y-7306D01*
X2357923Y-7806D01*
X2358303Y-8140D01*
X2358746Y-8223D01*
X2359189Y-8056D01*
X2359633Y-7556D01*
G01X2363656Y-8223D02*
Y-3223D01*
G01X2372589Y-8223D02*
Y-3223D01*
X2374173D01*
X2374679Y-3473D01*
X2374996Y-3806D01*
X2375123Y-4473D01*
X2374996Y-5140D01*
X2374616Y-5556D01*
X2374173Y-5806D01*
X2372589D01*
G01X2374173D02*
X2375123Y-8223D01*
G01X2378006Y-5973D02*
X2380033D01*
X2379843Y-5390D01*
X2379526Y-5056D01*
X2379083Y-4890D01*
X2378639Y-4973D01*
X2378259Y-5223D01*
X2378006Y-5806D01*
X2377879Y-6306D01*
Y-6806D01*
X2378006Y-7306D01*
X2378323Y-7806D01*
X2378703Y-8140D01*
X2379146Y-8223D01*
X2379589Y-8056D01*
X2380033Y-7556D01*
G01X2382916Y-4890D02*
X2384056Y-8223D01*
X2385196Y-4890D01*
G01X2394763Y-5556D02*
X2395016Y-5306D01*
X2395206Y-4890D01*
X2395333Y-4306D01*
X2395206Y-3806D01*
X2394953Y-3473D01*
X2394509Y-3223D01*
X2392799D01*
Y-8223D01*
X2394889D01*
X2395333Y-7890D01*
X2395586Y-7390D01*
X2395713Y-6806D01*
X2395586Y-6223D01*
X2395206Y-5723D01*
X2394763Y-5556D01*
X2392799D01*
G01X-1490433Y-1677216D02*
Y3837819D01*
X4496476D01*
Y-1677216D01*
X-1490433D01*
G01X-7782Y-515685D02*
X-6215D01*
Y-517575D01*
X-6685Y-518205D01*
X-7234Y-518625D01*
X-8017Y-518835D01*
X-8800Y-518625D01*
X-9349Y-518205D01*
X-9819Y-517575D01*
X-10132Y-516840D01*
X-10289Y-516000D01*
Y-515265D01*
X-10132Y-514635D01*
X-9819Y-513900D01*
X-9349Y-513270D01*
X-8879Y-512850D01*
X-8252Y-512535D01*
X-7704D01*
X-7077Y-512745D01*
X-6607Y-513165D01*
G01X-3675Y-512535D02*
Y-517050D01*
X-3362Y-517995D01*
X-2735Y-518625D01*
X-1952Y-518835D01*
X-1169Y-518625D01*
X-542Y-517995D01*
X-229Y-517050D01*
Y-512535D01*
G01X3408D02*
X5288D01*
G01X4348D02*
Y-518835D01*
G01X3408D02*
X5288D01*
G01X9003Y-517995D02*
X9630Y-518520D01*
X10335Y-518835D01*
X10961D01*
X11588Y-518520D01*
X12058Y-517995D01*
X12293Y-517260D01*
X12136Y-516525D01*
X11745Y-515895D01*
X11040Y-515475D01*
X10100Y-515265D01*
X9551Y-514845D01*
X9316Y-514110D01*
X9473Y-513375D01*
X9865Y-512850D01*
X10413Y-512535D01*
X10961D01*
X11510Y-512745D01*
X11980Y-513270D01*
G01X15303Y-518835D02*
Y-512535D01*
G01X18593D02*
Y-518835D01*
G01Y-515685D02*
X15303D01*
G01X21290Y-518835D02*
X23248Y-512535D01*
X25206Y-518835D01*
G01X24501Y-516630D02*
X21995D01*
G01X27746Y-518835D02*
Y-512535D01*
X31350Y-518835D01*
Y-512535D01*
G01X40425Y-518835D02*
Y-512535D01*
X41991D01*
X42618Y-512850D01*
X43088Y-513270D01*
X43480Y-513900D01*
X43793Y-514635D01*
X43871Y-515685D01*
X43793Y-516735D01*
X43480Y-517470D01*
X43088Y-518100D01*
X42618Y-518520D01*
X41991Y-518835D01*
X40425D01*
G01X47508Y-512535D02*
X49388D01*
G01X48448D02*
Y-518835D01*
G01X47508D02*
X49388D01*
G01X53103Y-517995D02*
X53730Y-518520D01*
X54435Y-518835D01*
X55061D01*
X55688Y-518520D01*
X56158Y-517995D01*
X56393Y-517260D01*
X56236Y-516525D01*
X55845Y-515895D01*
X55140Y-515475D01*
X54200Y-515265D01*
X53651Y-514845D01*
X53416Y-514110D01*
X53573Y-513375D01*
X53965Y-512850D01*
X54513Y-512535D01*
X55061D01*
X55610Y-512745D01*
X56080Y-513270D01*
G01X61048Y-512535D02*
Y-518835D01*
G01X59246Y-512535D02*
X62850D01*
G01X67348Y-519045D02*
X67191Y-518940D01*
Y-518730D01*
X67348Y-518625D01*
X67505Y-518730D01*
Y-518940D01*
X67348Y-519045D01*
G01X73491Y-519990D02*
X73805Y-518625D01*
G01X79948Y-512535D02*
Y-518835D01*
G01X78146Y-512535D02*
X81750D01*
G01X84290Y-518835D02*
X86248Y-512535D01*
X88206Y-518835D01*
G01X87501Y-516630D02*
X84995D01*
G01X92548Y-518835D02*
X91921Y-518730D01*
X91373Y-518310D01*
X90903Y-517680D01*
X90590Y-516945D01*
X90433Y-516105D01*
Y-515265D01*
X90590Y-514425D01*
X90903Y-513690D01*
X91373Y-513060D01*
X91921Y-512640D01*
X92548Y-512535D01*
X93175Y-512640D01*
X93723Y-513060D01*
X94193Y-513690D01*
X94506Y-514425D01*
X94663Y-515265D01*
Y-516105D01*
X94506Y-516945D01*
X94193Y-517680D01*
X93723Y-518310D01*
X93175Y-518730D01*
X92548Y-518835D01*
G01X98848D02*
Y-516000D01*
X97281Y-512535D01*
G01X100415D02*
X98848Y-516000D01*
G01X103425Y-512535D02*
Y-517050D01*
X103738Y-517995D01*
X104365Y-518625D01*
X105148Y-518835D01*
X105931Y-518625D01*
X106558Y-517995D01*
X106871Y-517050D01*
Y-512535D01*
G01X109490Y-518835D02*
X111448Y-512535D01*
X113406Y-518835D01*
G01X112701Y-516630D02*
X110195D01*
G01X115946Y-518835D02*
Y-512535D01*
X119550Y-518835D01*
Y-512535D01*
G01X-6529Y-523060D02*
X-6999Y-522745D01*
X-7547Y-522535D01*
X-8174D01*
X-8879Y-522850D01*
X-9427Y-523375D01*
X-9819Y-524005D01*
X-10132Y-525055D01*
X-10210Y-526000D01*
X-10054Y-526945D01*
X-9819Y-527575D01*
X-9349Y-528205D01*
X-8800Y-528625D01*
X-8252Y-528835D01*
X-7704D01*
X-7155Y-528625D01*
X-6685Y-528310D01*
X-6294Y-527890D01*
G01X-2892Y-522535D02*
X-1012D01*
G01X-1952D02*
Y-528835D01*
G01X-2892D02*
X-1012D01*
G01X4348Y-522535D02*
Y-528835D01*
G01X2546Y-522535D02*
X6150D01*
G01X10648Y-528835D02*
Y-526000D01*
X9081Y-522535D01*
G01X12215D02*
X10648Y-526000D01*
G01X21525Y-527575D02*
X21995Y-528310D01*
X22621Y-528730D01*
X23326Y-528835D01*
X23953Y-528730D01*
X24580Y-528205D01*
X24971Y-527575D01*
X25050Y-526945D01*
X24893Y-526210D01*
X24345Y-525685D01*
X23796Y-525475D01*
X23091D01*
G01X23796D02*
X24266Y-525160D01*
X24658Y-524635D01*
X24815Y-524005D01*
X24658Y-523375D01*
X24266Y-522850D01*
X23561Y-522535D01*
X22856Y-522640D01*
X22151Y-523060D01*
G01X27825Y-527575D02*
X28295Y-528310D01*
X28921Y-528730D01*
X29626Y-528835D01*
X30253Y-528730D01*
X30880Y-528205D01*
X31271Y-527575D01*
X31350Y-526945D01*
X31193Y-526210D01*
X30645Y-525685D01*
X30096Y-525475D01*
X29391D01*
G01X30096D02*
X30566Y-525160D01*
X30958Y-524635D01*
X31115Y-524005D01*
X30958Y-523375D01*
X30566Y-522850D01*
X29861Y-522535D01*
X29156Y-522640D01*
X28451Y-523060D01*
G01X34125Y-527575D02*
X34595Y-528310D01*
X35221Y-528730D01*
X35926Y-528835D01*
X36553Y-528730D01*
X37180Y-528205D01*
X37571Y-527575D01*
X37650Y-526945D01*
X37493Y-526210D01*
X36945Y-525685D01*
X36396Y-525475D01*
X35691D01*
G01X36396D02*
X36866Y-525160D01*
X37258Y-524635D01*
X37415Y-524005D01*
X37258Y-523375D01*
X36866Y-522850D01*
X36161Y-522535D01*
X35456Y-522640D01*
X34751Y-523060D01*
G01X41991Y-528835D02*
X42148Y-527470D01*
X42383Y-526315D01*
X42696Y-525265D01*
X43088Y-524110D01*
X43715Y-522535D01*
X40581D01*
G01X48291Y-528835D02*
X48448Y-527470D01*
X48683Y-526315D01*
X48996Y-525265D01*
X49388Y-524110D01*
X50015Y-522535D01*
X46881D01*
G01X54591Y-529990D02*
X54905Y-528625D01*
G01X61048Y-522535D02*
Y-528835D01*
G01X59246Y-522535D02*
X62850D01*
G01X65390Y-528835D02*
X67348Y-522535D01*
X69306Y-528835D01*
G01X68601Y-526630D02*
X66095D01*
G01X72708Y-522535D02*
X74588D01*
G01X73648D02*
Y-528835D01*
G01X72708D02*
X74588D01*
G01X77598Y-522535D02*
X78695Y-528835D01*
X79948Y-522535D01*
X81201Y-528835D01*
X82298Y-522535D01*
G01X84290Y-528835D02*
X86248Y-522535D01*
X88206Y-528835D01*
G01X87501Y-526630D02*
X84995D01*
G01X90746Y-528835D02*
Y-522535D01*
X94350Y-528835D01*
Y-522535D01*
G01X104756Y-530935D02*
X103973Y-529885D01*
X103581Y-528835D01*
Y-524635D01*
X103973Y-523585D01*
X104756Y-522535D01*
G01X116181Y-528835D02*
Y-522535D01*
X118140D01*
X118766Y-522850D01*
X119158Y-523270D01*
X119315Y-524110D01*
X119158Y-524950D01*
X118688Y-525475D01*
X118140Y-525790D01*
X116181D01*
G01X118140D02*
X119315Y-528835D01*
G01X124048Y-529045D02*
X123891Y-528940D01*
Y-528730D01*
X124048Y-528625D01*
X124205Y-528730D01*
Y-528940D01*
X124048Y-529045D01*
G01X130348Y-528835D02*
X129721Y-528730D01*
X129173Y-528310D01*
X128703Y-527680D01*
X128390Y-526945D01*
X128233Y-526105D01*
Y-525265D01*
X128390Y-524425D01*
X128703Y-523690D01*
X129173Y-523060D01*
X129721Y-522640D01*
X130348Y-522535D01*
X130975Y-522640D01*
X131523Y-523060D01*
X131993Y-523690D01*
X132306Y-524425D01*
X132463Y-525265D01*
Y-526105D01*
X132306Y-526945D01*
X131993Y-527680D01*
X131523Y-528310D01*
X130975Y-528730D01*
X130348Y-528835D01*
G01X136648Y-529045D02*
X136491Y-528940D01*
Y-528730D01*
X136648Y-528625D01*
X136805Y-528730D01*
Y-528940D01*
X136648Y-529045D01*
G01X144671Y-523060D02*
X144201Y-522745D01*
X143653Y-522535D01*
X143026D01*
X142321Y-522850D01*
X141773Y-523375D01*
X141381Y-524005D01*
X141068Y-525055D01*
X140990Y-526000D01*
X141146Y-526945D01*
X141381Y-527575D01*
X141851Y-528205D01*
X142400Y-528625D01*
X142948Y-528835D01*
X143496D01*
X144045Y-528625D01*
X144515Y-528310D01*
X144906Y-527890D01*
G01X149248Y-529045D02*
X149091Y-528940D01*
Y-528730D01*
X149248Y-528625D01*
X149405Y-528730D01*
Y-528940D01*
X149248Y-529045D01*
G01X155940Y-530935D02*
X156723Y-529885D01*
X157115Y-528835D01*
Y-524635D01*
X156723Y-523585D01*
X155940Y-522535D01*
G01X-10054Y-508835D02*
Y-502535D01*
X-6450Y-508835D01*
Y-502535D01*
G01X-1952Y-508835D02*
X-2579Y-508730D01*
X-3127Y-508310D01*
X-3597Y-507680D01*
X-3910Y-506945D01*
X-4067Y-506105D01*
Y-505265D01*
X-3910Y-504425D01*
X-3597Y-503690D01*
X-3127Y-503060D01*
X-2579Y-502640D01*
X-1952Y-502535D01*
X-1325Y-502640D01*
X-777Y-503060D01*
X-307Y-503690D01*
X6Y-504425D01*
X163Y-505265D01*
Y-506105D01*
X6Y-506945D01*
X-307Y-507680D01*
X-777Y-508310D01*
X-1325Y-508730D01*
X-1952Y-508835D01*
G01X4348Y-509045D02*
X4191Y-508940D01*
Y-508730D01*
X4348Y-508625D01*
X4505Y-508730D01*
Y-508940D01*
X4348Y-509045D01*
G01X9160Y-503585D02*
X9630Y-502955D01*
X10178Y-502640D01*
X10805Y-502535D01*
X11588Y-502745D01*
X12136Y-503270D01*
X12293Y-503900D01*
X12215Y-504530D01*
X11901Y-505055D01*
X10335Y-506105D01*
X9630Y-506840D01*
X9160Y-507890D01*
X9003Y-508835D01*
X12293D01*
G01X16948D02*
Y-502535D01*
X16008Y-503795D01*
G01Y-508835D02*
X17888D01*
G01X23248D02*
Y-502535D01*
X22308Y-503795D01*
G01Y-508835D02*
X24188D01*
G01X29391Y-509990D02*
X29705Y-508625D01*
G01X33498Y-502535D02*
X34595Y-508835D01*
X35848Y-502535D01*
X37101Y-508835D01*
X38198Y-502535D01*
G01X43715Y-508835D02*
X40581D01*
Y-502535D01*
X43715D01*
G01X42461Y-505580D02*
X40581D01*
G01X46646Y-508835D02*
Y-502535D01*
X50250Y-508835D01*
Y-502535D01*
G01X53103Y-508835D02*
Y-502535D01*
G01X56393D02*
Y-508835D01*
G01Y-505685D02*
X53103D01*
G01X59325Y-502535D02*
Y-507050D01*
X59638Y-507995D01*
X60265Y-508625D01*
X61048Y-508835D01*
X61831Y-508625D01*
X62458Y-507995D01*
X62771Y-507050D01*
Y-502535D01*
G01X65390Y-508835D02*
X67348Y-502535D01*
X69306Y-508835D01*
G01X68601Y-506630D02*
X66095D01*
G01X78460Y-503585D02*
X78930Y-502955D01*
X79478Y-502640D01*
X80105Y-502535D01*
X80888Y-502745D01*
X81436Y-503270D01*
X81593Y-503900D01*
X81515Y-504530D01*
X81201Y-505055D01*
X79635Y-506105D01*
X78930Y-506840D01*
X78460Y-507890D01*
X78303Y-508835D01*
X81593D01*
G01X84446D02*
Y-502535D01*
X88050Y-508835D01*
Y-502535D01*
G01X90825Y-508835D02*
Y-502535D01*
X92391D01*
X93018Y-502850D01*
X93488Y-503270D01*
X93880Y-503900D01*
X94193Y-504635D01*
X94271Y-505685D01*
X94193Y-506735D01*
X93880Y-507470D01*
X93488Y-508100D01*
X93018Y-508520D01*
X92391Y-508835D01*
X90825D01*
G01X103581D02*
Y-502535D01*
X105540D01*
X106166Y-502850D01*
X106558Y-503270D01*
X106715Y-504110D01*
X106558Y-504950D01*
X106088Y-505475D01*
X105540Y-505790D01*
X103581D01*
G01X105540D02*
X106715Y-508835D01*
G01X109725D02*
Y-502535D01*
X111291D01*
X111918Y-502850D01*
X112388Y-503270D01*
X112780Y-503900D01*
X113093Y-504635D01*
X113171Y-505685D01*
X113093Y-506735D01*
X112780Y-507470D01*
X112388Y-508100D01*
X111918Y-508520D01*
X111291Y-508835D01*
X109725D01*
G01X117748Y-509045D02*
X117591Y-508940D01*
Y-508730D01*
X117748Y-508625D01*
X117905Y-508730D01*
Y-508940D01*
X117748Y-509045D01*
G01X14048Y-498135D02*
X11528Y-497718D01*
X9323Y-496052D01*
X7433Y-493552D01*
X6173Y-490635D01*
X5543Y-487302D01*
Y-483968D01*
X6173Y-480635D01*
X7433Y-477718D01*
X9323Y-475219D01*
X11528Y-473552D01*
X14048Y-473135D01*
X16568Y-473552D01*
X18773Y-475219D01*
X20663Y-477718D01*
X21923Y-480635D01*
X22553Y-483968D01*
Y-487302D01*
X21923Y-490635D01*
X20663Y-493552D01*
X18773Y-496052D01*
X16568Y-497718D01*
X14048Y-498135D01*
G01X16568Y-491468D02*
X20348Y-498135D01*
G01X33893Y-481469D02*
Y-493135D01*
X35153Y-496052D01*
X37043Y-497718D01*
X39248Y-498135D01*
X41453Y-497718D01*
X43343Y-496052D01*
X44603Y-493135D01*
G01Y-498135D02*
Y-481469D01*
G01X70118Y-498135D02*
Y-481469D01*
G01Y-484385D02*
X68858Y-482719D01*
X66968Y-481885D01*
X64763Y-481469D01*
X62558Y-482302D01*
X60668Y-483968D01*
X59408Y-486469D01*
X58778Y-489802D01*
X59408Y-493135D01*
X60668Y-495636D01*
X62558Y-497302D01*
X64763Y-498135D01*
X66968Y-497718D01*
X68858Y-496469D01*
X70118Y-494802D01*
G01X84293Y-498135D02*
Y-481469D01*
G01Y-485635D02*
X85553Y-483552D01*
X87443Y-481885D01*
X89963Y-481469D01*
X92168Y-481885D01*
X94058Y-483552D01*
X95003Y-486469D01*
Y-498135D01*
G01X114848Y-473135D02*
Y-498135D01*
G01X110438Y-481469D02*
X119258D01*
G01X145718Y-498135D02*
Y-481469D01*
G01Y-484385D02*
X144458Y-482719D01*
X142568Y-481885D01*
X140363Y-481469D01*
X138158Y-482302D01*
X136268Y-483968D01*
X135008Y-486469D01*
X134378Y-489802D01*
X135008Y-493135D01*
X136268Y-495636D01*
X138158Y-497302D01*
X140363Y-498135D01*
X142568Y-497718D01*
X144458Y-496469D01*
X145718Y-494802D01*
G01X25935Y-83298D02*
G03I-6250J0D01*
G01Y1801195D02*
G03I-6250J0D01*
G01X53149Y-83298D02*
G03I-5905J0D01*
G01X87758Y-60383D02*
X92438D01*
G01X90098D02*
Y-75983D01*
G01X87758D02*
X92438D01*
G01X103903Y-73903D02*
X105463Y-75203D01*
X107218Y-75983D01*
X108778D01*
X110338Y-75203D01*
X111508Y-73903D01*
X112093Y-72083D01*
X111703Y-70263D01*
X110728Y-68703D01*
X108973Y-67663D01*
X106633Y-67143D01*
X105268Y-66103D01*
X104683Y-64283D01*
X105073Y-62463D01*
X106048Y-61163D01*
X107413Y-60383D01*
X108778D01*
X110143Y-60903D01*
X111313Y-62203D01*
G01X125898Y-60383D02*
Y-75983D01*
G01X121413Y-60383D02*
X130383D01*
G01X162868Y-68183D02*
X166768D01*
Y-72863D01*
X165598Y-74423D01*
X164233Y-75463D01*
X162283Y-75983D01*
X160333Y-75463D01*
X158968Y-74423D01*
X157798Y-72863D01*
X157018Y-71043D01*
X156628Y-68963D01*
Y-67143D01*
X157018Y-65583D01*
X157798Y-63763D01*
X158968Y-62203D01*
X160138Y-61163D01*
X161698Y-60383D01*
X163063D01*
X164623Y-60903D01*
X165793Y-61943D01*
G01X183498Y-75983D02*
X175698D01*
Y-60383D01*
X183498D01*
G01X180378Y-67923D02*
X175698D01*
G01X193598Y-75983D02*
Y-60383D01*
X198473D01*
X200033Y-61163D01*
X201008Y-62203D01*
X201398Y-64283D01*
X201008Y-66363D01*
X199838Y-67663D01*
X198473Y-68443D01*
X193598D01*
G01X198473D02*
X201398Y-75983D01*
G01X216958Y-67663D02*
X217738Y-66883D01*
X218323Y-65583D01*
X218713Y-63763D01*
X218323Y-62203D01*
X217543Y-61163D01*
X216178Y-60383D01*
X210913D01*
Y-75983D01*
X217348D01*
X218713Y-74943D01*
X219493Y-73383D01*
X219883Y-71563D01*
X219493Y-69743D01*
X218323Y-68183D01*
X216958Y-67663D01*
X210913D01*
G01X237198Y-75983D02*
X229398D01*
Y-60383D01*
X237198D01*
G01X234078Y-67923D02*
X229398D01*
G01X247298Y-75983D02*
Y-60383D01*
X252173D01*
X253733Y-61163D01*
X254708Y-62203D01*
X255098Y-64283D01*
X254708Y-66363D01*
X253538Y-67663D01*
X252173Y-68443D01*
X247298D01*
G01X252173D02*
X255098Y-75983D01*
G01X268123Y-81183D02*
X266173Y-78583D01*
X265198Y-75983D01*
Y-65583D01*
X266173Y-62983D01*
X268123Y-60383D01*
G01X291288Y-61683D02*
X290118Y-60903D01*
X288753Y-60383D01*
X287193D01*
X285438Y-61163D01*
X284073Y-62463D01*
X283098Y-64023D01*
X282318Y-66623D01*
X282123Y-68963D01*
X282513Y-71303D01*
X283098Y-72863D01*
X284268Y-74423D01*
X285633Y-75463D01*
X286998Y-75983D01*
X288363D01*
X289728Y-75463D01*
X290898Y-74683D01*
X291873Y-73643D01*
G01X306458Y-67663D02*
X307238Y-66883D01*
X307823Y-65583D01*
X308213Y-63763D01*
X307823Y-62203D01*
X307043Y-61163D01*
X305678Y-60383D01*
X300413D01*
Y-75983D01*
X306848D01*
X308213Y-74943D01*
X308993Y-73383D01*
X309383Y-71563D01*
X308993Y-69743D01*
X307823Y-68183D01*
X306458Y-67663D01*
X300413D01*
G01X318703Y-75983D02*
X326893Y-60383D01*
G01X318703D02*
X326893Y-75983D01*
G01X340698D02*
Y-60383D01*
X338358Y-63503D01*
G01Y-75983D02*
X343038D01*
G01X358598D02*
X359963Y-75723D01*
X361523Y-74943D01*
X362498Y-73643D01*
X362888Y-71823D01*
X362498Y-70003D01*
X361328Y-68443D01*
X359573Y-67663D01*
X357623D01*
X356453Y-67143D01*
X355478Y-65843D01*
X355088Y-64023D01*
X355673Y-62203D01*
X357038Y-60903D01*
X358598Y-60383D01*
X360158Y-60903D01*
X361523Y-62203D01*
X362108Y-64023D01*
X361718Y-65843D01*
X360743Y-67143D01*
X359573Y-67663D01*
X357623D01*
X355868Y-68443D01*
X354698Y-70003D01*
X354308Y-71823D01*
X354698Y-73643D01*
X355673Y-74943D01*
X357233Y-75723D01*
X358598Y-75983D01*
G01X376498Y-60383D02*
X374938Y-60903D01*
X373768Y-62203D01*
X372988Y-63763D01*
X372403Y-65843D01*
X372208Y-68183D01*
X372403Y-70523D01*
X372988Y-72603D01*
X373768Y-74163D01*
X374938Y-75463D01*
X376498Y-75983D01*
X378058Y-75463D01*
X379228Y-74163D01*
X380008Y-72603D01*
X380593Y-70523D01*
X380788Y-68183D01*
X380593Y-65843D01*
X380008Y-63763D01*
X379228Y-62203D01*
X378058Y-60903D01*
X376498Y-60383D01*
G01X396738Y-75983D02*
Y-60383D01*
X389523Y-71563D01*
X399273D01*
G01X412298Y-75983D02*
X413663Y-75723D01*
X415223Y-74943D01*
X416198Y-73643D01*
X416588Y-71823D01*
X416198Y-70003D01*
X415028Y-68443D01*
X413273Y-67663D01*
X411323D01*
X410153Y-67143D01*
X409178Y-65843D01*
X408788Y-64023D01*
X409373Y-62203D01*
X410738Y-60903D01*
X412298Y-60383D01*
X413858Y-60903D01*
X415223Y-62203D01*
X415808Y-64023D01*
X415418Y-65843D01*
X414443Y-67143D01*
X413273Y-67663D01*
X411323D01*
X409568Y-68443D01*
X408398Y-70003D01*
X408008Y-71823D01*
X408398Y-73643D01*
X409373Y-74943D01*
X410933Y-75723D01*
X412298Y-75983D01*
G01X425323D02*
X430198Y-60383D01*
X435073Y-75983D01*
G01X433318Y-70523D02*
X427078D01*
G01X449073Y-81183D02*
X451023Y-78583D01*
X451998Y-75983D01*
Y-65583D01*
X451023Y-62983D01*
X449073Y-60383D01*
G01X185398Y-477835D02*
Y-485835D01*
X189398D01*
G01X197198D02*
Y-480502D01*
G01Y-481435D02*
X196798Y-480902D01*
X196198Y-480635D01*
X195498Y-480502D01*
X194798Y-480768D01*
X194198Y-481302D01*
X193798Y-482102D01*
X193598Y-483168D01*
X193798Y-484235D01*
X194198Y-485035D01*
X194798Y-485568D01*
X195498Y-485835D01*
X196198Y-485702D01*
X196798Y-485302D01*
X197198Y-484769D01*
G01X201298Y-488235D02*
X201898Y-488502D01*
X202698Y-488235D01*
X203198Y-487702D01*
X203598Y-487035D01*
X204198Y-484902D01*
X205498Y-480502D01*
G01X202298D02*
X204198Y-484902D01*
G01X209898Y-482235D02*
X213098D01*
X212798Y-481302D01*
X212298Y-480768D01*
X211598Y-480502D01*
X210898Y-480635D01*
X210298Y-481035D01*
X209898Y-481968D01*
X209698Y-482769D01*
Y-483568D01*
X209898Y-484368D01*
X210398Y-485168D01*
X210998Y-485702D01*
X211698Y-485835D01*
X212398Y-485568D01*
X213098Y-484769D01*
G01X217998Y-485835D02*
Y-480502D01*
G01Y-481568D02*
X218498Y-481035D01*
X218998Y-480635D01*
X219698Y-480502D01*
X220198Y-480635D01*
X220798Y-481035D01*
G01X211398Y-535835D02*
Y-532235D01*
X209398Y-527835D01*
G01X213398D02*
X211398Y-532235D01*
G01X217698Y-530502D02*
Y-534235D01*
X218098Y-535168D01*
X218698Y-535702D01*
X219398Y-535835D01*
X220098Y-535702D01*
X220698Y-535168D01*
X221098Y-534235D01*
G01Y-535835D02*
Y-530502D01*
G01X225698Y-535835D02*
Y-530502D01*
G01Y-531835D02*
X226098Y-531168D01*
X226698Y-530635D01*
X227498Y-530502D01*
X228198Y-530635D01*
X228798Y-531168D01*
X229098Y-532102D01*
Y-535835D01*
G01X237198D02*
Y-530502D01*
G01Y-531435D02*
X236798Y-530902D01*
X236198Y-530635D01*
X235498Y-530502D01*
X234798Y-530768D01*
X234198Y-531302D01*
X233798Y-532102D01*
X233598Y-533168D01*
X233798Y-534235D01*
X234198Y-535035D01*
X234798Y-535568D01*
X235498Y-535835D01*
X236198Y-535702D01*
X236798Y-535302D01*
X237198Y-534769D01*
G01X204398Y-510835D02*
Y-502835D01*
X206798D01*
X207598Y-503235D01*
X208198Y-504168D01*
X208398Y-505235D01*
X208198Y-506302D01*
X207698Y-507102D01*
X206798Y-507502D01*
X204398D01*
G01X211898Y-510835D02*
X214398Y-502835D01*
X216898Y-510835D01*
G01X215998Y-508035D02*
X212798D01*
G01X220098Y-510835D02*
Y-502835D01*
X224698Y-510835D01*
Y-502835D01*
G01X232398Y-510835D02*
X228398D01*
Y-502835D01*
X232398D01*
G01X230798Y-506702D02*
X228398D01*
G01X236398Y-502835D02*
Y-510835D01*
X240398D01*
G01X311998Y-529168D02*
X312598Y-528368D01*
X313298Y-527968D01*
X314098Y-527835D01*
X315098Y-528102D01*
X315798Y-528768D01*
X315998Y-529568D01*
X315898Y-530369D01*
X315498Y-531035D01*
X313498Y-532368D01*
X312598Y-533302D01*
X311998Y-534635D01*
X311798Y-535835D01*
X315998D01*
G01X321898Y-527835D02*
X321098Y-528102D01*
X320498Y-528768D01*
X320098Y-529568D01*
X319798Y-530635D01*
X319698Y-531835D01*
X319798Y-533035D01*
X320098Y-534102D01*
X320498Y-534902D01*
X321098Y-535568D01*
X321898Y-535835D01*
X322698Y-535568D01*
X323298Y-534902D01*
X323698Y-534102D01*
X323998Y-533035D01*
X324098Y-531835D01*
X323998Y-530635D01*
X323698Y-529568D01*
X323298Y-528768D01*
X322698Y-528102D01*
X321898Y-527835D01*
G01X327998Y-529168D02*
X328598Y-528368D01*
X329298Y-527968D01*
X330098Y-527835D01*
X331098Y-528102D01*
X331798Y-528768D01*
X331998Y-529568D01*
X331898Y-530369D01*
X331498Y-531035D01*
X329498Y-532368D01*
X328598Y-533302D01*
X327998Y-534635D01*
X327798Y-535835D01*
X331998D01*
G01X335698Y-534235D02*
X336298Y-535168D01*
X337098Y-535702D01*
X337998Y-535835D01*
X338798Y-535702D01*
X339598Y-535035D01*
X340098Y-534235D01*
X340198Y-533435D01*
X339998Y-532502D01*
X339298Y-531835D01*
X338598Y-531568D01*
X337698D01*
G01X338598D02*
X339198Y-531168D01*
X339698Y-530502D01*
X339898Y-529702D01*
X339698Y-528902D01*
X339198Y-528235D01*
X338298Y-527835D01*
X337398Y-527968D01*
X336498Y-528502D01*
G01X344098Y-536102D02*
X347698Y-527835D01*
G01X353898D02*
X353098Y-528102D01*
X352498Y-528768D01*
X352098Y-529568D01*
X351798Y-530635D01*
X351698Y-531835D01*
X351798Y-533035D01*
X352098Y-534102D01*
X352498Y-534902D01*
X353098Y-535568D01*
X353898Y-535835D01*
X354698Y-535568D01*
X355298Y-534902D01*
X355698Y-534102D01*
X355998Y-533035D01*
X356098Y-531835D01*
X355998Y-530635D01*
X355698Y-529568D01*
X355298Y-528768D01*
X354698Y-528102D01*
X353898Y-527835D01*
G01X361898Y-535835D02*
Y-527835D01*
X360698Y-529435D01*
G01Y-535835D02*
X363098D01*
G01X368098Y-536102D02*
X371698Y-527835D01*
G01X377898D02*
X377098Y-528102D01*
X376498Y-528768D01*
X376098Y-529568D01*
X375798Y-530635D01*
X375698Y-531835D01*
X375798Y-533035D01*
X376098Y-534102D01*
X376498Y-534902D01*
X377098Y-535568D01*
X377898Y-535835D01*
X378698Y-535568D01*
X379298Y-534902D01*
X379698Y-534102D01*
X379998Y-533035D01*
X380098Y-531835D01*
X379998Y-530635D01*
X379698Y-529568D01*
X379298Y-528768D01*
X378698Y-528102D01*
X377898Y-527835D01*
G01X384198Y-534902D02*
X384898Y-535568D01*
X385698Y-535835D01*
X386498Y-535568D01*
X387198Y-534769D01*
X387698Y-533568D01*
X387898Y-532368D01*
Y-530902D01*
X387698Y-529702D01*
X387198Y-528635D01*
X386598Y-528102D01*
X385898Y-527835D01*
X385098Y-528102D01*
X384498Y-528635D01*
X384098Y-529435D01*
X383898Y-530502D01*
X384098Y-531435D01*
X384598Y-532368D01*
X385198Y-532902D01*
X385898Y-533035D01*
X386698Y-532769D01*
X387298Y-532102D01*
X387898Y-530902D01*
G01X311698Y-510835D02*
Y-502835D01*
X313698D01*
X314498Y-503235D01*
X315098Y-503768D01*
X315598Y-504568D01*
X315998Y-505502D01*
X316098Y-506835D01*
X315998Y-508168D01*
X315598Y-509102D01*
X315098Y-509902D01*
X314498Y-510435D01*
X313698Y-510835D01*
X311698D01*
G01X319398D02*
X321898Y-502835D01*
X324398Y-510835D01*
G01X323498Y-508035D02*
X320298D01*
G01X329898Y-502835D02*
X329098Y-503102D01*
X328498Y-503768D01*
X328098Y-504568D01*
X327798Y-505635D01*
X327698Y-506835D01*
X327798Y-508035D01*
X328098Y-509102D01*
X328498Y-509902D01*
X329098Y-510568D01*
X329898Y-510835D01*
X330698Y-510568D01*
X331298Y-509902D01*
X331698Y-509102D01*
X331998Y-508035D01*
X332098Y-506835D01*
X331998Y-505635D01*
X331698Y-504568D01*
X331298Y-503768D01*
X330698Y-503102D01*
X329898Y-502835D01*
G01X335998Y-510835D02*
Y-502835D01*
X339798D01*
G01X338398Y-506702D02*
X335998D01*
G01X345898Y-502835D02*
X345098Y-503102D01*
X344498Y-503768D01*
X344098Y-504568D01*
X343798Y-505635D01*
X343698Y-506835D01*
X343798Y-508035D01*
X344098Y-509102D01*
X344498Y-509902D01*
X345098Y-510568D01*
X345898Y-510835D01*
X346698Y-510568D01*
X347298Y-509902D01*
X347698Y-509102D01*
X347998Y-508035D01*
X348098Y-506835D01*
X347998Y-505635D01*
X347698Y-504568D01*
X347298Y-503768D01*
X346698Y-503102D01*
X345898Y-502835D01*
G01X353898D02*
Y-510835D01*
G01X351598Y-502835D02*
X356198D01*
G01X363898Y-510835D02*
X359898D01*
Y-502835D01*
X363898D01*
G01X362298Y-506702D02*
X359898D01*
G01X370698Y-506568D02*
X371098Y-506168D01*
X371398Y-505502D01*
X371598Y-504568D01*
X371398Y-503768D01*
X370998Y-503235D01*
X370298Y-502835D01*
X367598D01*
Y-510835D01*
X370898D01*
X371598Y-510302D01*
X371998Y-509502D01*
X372198Y-508568D01*
X371998Y-507635D01*
X371398Y-506835D01*
X370698Y-506568D01*
X367598D01*
G01X376698Y-502835D02*
X379098D01*
G01X377898D02*
Y-510835D01*
G01X376698D02*
X379098D01*
G01X383998D02*
Y-502835D01*
X387798D01*
G01X386398Y-506702D02*
X383998D01*
G01X393898Y-502835D02*
X393098Y-503102D01*
X392498Y-503768D01*
X392098Y-504568D01*
X391798Y-505635D01*
X391698Y-506835D01*
X391798Y-508035D01*
X392098Y-509102D01*
X392498Y-509902D01*
X393098Y-510568D01*
X393898Y-510835D01*
X394698Y-510568D01*
X395298Y-509902D01*
X395698Y-509102D01*
X395998Y-508035D01*
X396098Y-506835D01*
X395998Y-505635D01*
X395698Y-504568D01*
X395298Y-503768D01*
X394698Y-503102D01*
X393898Y-502835D01*
G01X329498Y-485835D02*
Y-477835D01*
X333298D01*
G01X331898Y-481702D02*
X329498D01*
G01X339398Y-477835D02*
X338598Y-478102D01*
X337998Y-478768D01*
X337598Y-479568D01*
X337298Y-480635D01*
X337198Y-481835D01*
X337298Y-483035D01*
X337598Y-484102D01*
X337998Y-484902D01*
X338598Y-485568D01*
X339398Y-485835D01*
X340198Y-485568D01*
X340798Y-484902D01*
X341198Y-484102D01*
X341498Y-483035D01*
X341598Y-481835D01*
X341498Y-480635D01*
X341198Y-479568D01*
X340798Y-478768D01*
X340198Y-478102D01*
X339398Y-477835D01*
G01X347398D02*
Y-485835D01*
G01X345098Y-477835D02*
X349698D01*
G01X352398Y-488502D02*
X358398D01*
G01X361898Y-482235D02*
X365098D01*
X364798Y-481302D01*
X364298Y-480768D01*
X363598Y-480502D01*
X362898Y-480635D01*
X362298Y-481035D01*
X361898Y-481968D01*
X361698Y-482769D01*
Y-483568D01*
X361898Y-484368D01*
X362398Y-485168D01*
X362998Y-485702D01*
X363698Y-485835D01*
X364398Y-485568D01*
X365098Y-484769D01*
G01X369898Y-480502D02*
X372898Y-485835D01*
G01Y-480502D02*
X369898Y-485835D01*
G01X377598Y-488502D02*
Y-480502D01*
G01Y-481702D02*
X378098Y-481035D01*
X378598Y-480635D01*
X379398Y-480502D01*
X380098Y-480635D01*
X380798Y-481302D01*
X381098Y-482235D01*
X381198Y-483168D01*
X381098Y-484102D01*
X380798Y-485035D01*
X380198Y-485568D01*
X379398Y-485835D01*
X378698Y-485702D01*
X377998Y-485302D01*
X377598Y-484769D01*
G01X389198Y-485835D02*
Y-480502D01*
G01Y-481435D02*
X388798Y-480902D01*
X388198Y-480635D01*
X387498Y-480502D01*
X386798Y-480768D01*
X386198Y-481302D01*
X385798Y-482102D01*
X385598Y-483168D01*
X385798Y-484235D01*
X386198Y-485035D01*
X386798Y-485568D01*
X387498Y-485835D01*
X388198Y-485702D01*
X388798Y-485302D01*
X389198Y-484769D01*
G01X393698Y-485835D02*
Y-480502D01*
G01Y-481835D02*
X394098Y-481168D01*
X394698Y-480635D01*
X395498Y-480502D01*
X396198Y-480635D01*
X396798Y-481168D01*
X397098Y-482102D01*
Y-485835D01*
G01X405198Y-477835D02*
Y-485835D01*
G01Y-484635D02*
X404798Y-485302D01*
X404198Y-485702D01*
X403498Y-485835D01*
X402698Y-485568D01*
X402098Y-484902D01*
X401698Y-484102D01*
X401598Y-483168D01*
X401698Y-482235D01*
X402098Y-481435D01*
X402698Y-480768D01*
X403498Y-480502D01*
X404198Y-480635D01*
X404698Y-480902D01*
X405198Y-481435D01*
G01X409898Y-482235D02*
X413098D01*
X412798Y-481302D01*
X412298Y-480768D01*
X411598Y-480502D01*
X410898Y-480635D01*
X410298Y-481035D01*
X409898Y-481968D01*
X409698Y-482769D01*
Y-483568D01*
X409898Y-484368D01*
X410398Y-485168D01*
X410998Y-485702D01*
X411698Y-485835D01*
X412398Y-485568D01*
X413098Y-484769D01*
G01X417998Y-485835D02*
Y-480502D01*
G01Y-481568D02*
X418498Y-481035D01*
X418998Y-480635D01*
X419698Y-480502D01*
X420198Y-480635D01*
X420798Y-481035D01*
G01X424398Y-488502D02*
X430398D01*
G01X433598Y-485835D02*
Y-477835D01*
G01Y-481835D02*
X434098Y-481035D01*
X434698Y-480635D01*
X435298Y-480502D01*
X436198Y-480768D01*
X436798Y-481302D01*
X437198Y-482235D01*
Y-483302D01*
X436998Y-484368D01*
X436598Y-485168D01*
X435898Y-485702D01*
X435298Y-485835D01*
X434698Y-485702D01*
X434098Y-485302D01*
X433598Y-484635D01*
G01X445198Y-477835D02*
Y-485835D01*
G01Y-484635D02*
X444798Y-485302D01*
X444198Y-485702D01*
X443498Y-485835D01*
X442698Y-485568D01*
X442098Y-484902D01*
X441698Y-484102D01*
X441598Y-483168D01*
X441698Y-482235D01*
X442098Y-481435D01*
X442698Y-480768D01*
X443498Y-480502D01*
X444198Y-480635D01*
X444698Y-480902D01*
X445198Y-481435D01*
G01X400398Y-538835D02*
Y-530835D01*
X399198Y-532435D01*
G01Y-538835D02*
X401598D01*
G01X406498Y-535502D02*
X407198Y-534568D01*
X407798Y-534035D01*
X408598Y-533768D01*
X409298Y-534035D01*
X409798Y-534568D01*
X410198Y-535368D01*
X410298Y-536302D01*
X410198Y-537102D01*
X409798Y-537902D01*
X409198Y-538568D01*
X408498Y-538835D01*
X407698Y-538568D01*
X406998Y-537769D01*
X406598Y-536568D01*
X406498Y-535235D01*
X406698Y-533502D01*
X406998Y-532568D01*
X407498Y-531635D01*
X408198Y-530968D01*
X408898Y-530835D01*
X409598Y-531102D01*
X410098Y-531768D01*
G01X416398Y-539102D02*
X416198Y-538968D01*
Y-538702D01*
X416398Y-538568D01*
X416598Y-538702D01*
Y-538968D01*
X416398Y-539102D01*
G01X422498Y-535502D02*
X423198Y-534568D01*
X423798Y-534035D01*
X424598Y-533768D01*
X425298Y-534035D01*
X425798Y-534568D01*
X426198Y-535368D01*
X426298Y-536302D01*
X426198Y-537102D01*
X425798Y-537902D01*
X425198Y-538568D01*
X424498Y-538835D01*
X423698Y-538568D01*
X422998Y-537769D01*
X422598Y-536568D01*
X422498Y-535235D01*
X422698Y-533502D01*
X422998Y-532568D01*
X423498Y-531635D01*
X424198Y-530968D01*
X424898Y-530835D01*
X425598Y-531102D01*
X426098Y-531768D01*
G01X445398Y-538835D02*
Y-530835D01*
X444198Y-532435D01*
G01Y-538835D02*
X446598D01*
G01X453198D02*
X453398Y-537102D01*
X453698Y-535635D01*
X454098Y-534302D01*
X454598Y-532835D01*
X455398Y-530835D01*
X451398D01*
G01X461398Y-539102D02*
X461198Y-538968D01*
Y-538702D01*
X461398Y-538568D01*
X461598Y-538702D01*
Y-538968D01*
X461398Y-539102D01*
G01X467498Y-532168D02*
X468098Y-531368D01*
X468798Y-530968D01*
X469598Y-530835D01*
X470598Y-531102D01*
X471298Y-531768D01*
X471498Y-532568D01*
X471398Y-533369D01*
X470998Y-534035D01*
X468998Y-535368D01*
X468098Y-536302D01*
X467498Y-537635D01*
X467298Y-538835D01*
X471498D01*
G01X465498Y-513835D02*
Y-505835D01*
X469298D01*
G01X467898Y-509702D02*
X465498D01*
G01X566888Y-58683D02*
X565718Y-57903D01*
X564353Y-57383D01*
X562793D01*
X561038Y-58163D01*
X559673Y-59463D01*
X558698Y-61023D01*
X557918Y-63623D01*
X557723Y-65963D01*
X558113Y-68303D01*
X558698Y-69863D01*
X559868Y-71423D01*
X561233Y-72463D01*
X562598Y-72983D01*
X563963D01*
X565328Y-72463D01*
X566498Y-71683D01*
X567473Y-70643D01*
G01X582058Y-64663D02*
X582838Y-63883D01*
X583423Y-62583D01*
X583813Y-60763D01*
X583423Y-59203D01*
X582643Y-58163D01*
X581278Y-57383D01*
X576013D01*
Y-72983D01*
X582448D01*
X583813Y-71943D01*
X584593Y-70383D01*
X584983Y-68563D01*
X584593Y-66743D01*
X583423Y-65183D01*
X582058Y-64663D01*
X576013D01*
G01X1156000Y1154000D02*
X755000D01*
X692000Y1091000D01*
Y322000D01*
G01X693500Y812000D02*
X1020000D01*
G01X877073Y1867130D02*
Y1879630D01*
X875213Y1877130D01*
G01Y1867130D02*
X878933D01*
G01X889473D02*
X890558Y1867338D01*
X891798Y1867963D01*
X892573Y1869005D01*
X892883Y1870463D01*
X892573Y1871921D01*
X891643Y1873172D01*
X890248Y1873797D01*
X888698D01*
X887768Y1874213D01*
X886993Y1875255D01*
X886683Y1876713D01*
X887148Y1878172D01*
X888233Y1879213D01*
X889473Y1879630D01*
X890713Y1879213D01*
X891798Y1878172D01*
X892263Y1876713D01*
X891953Y1875255D01*
X891178Y1874213D01*
X890248Y1873797D01*
X888698D01*
X887303Y1873172D01*
X886373Y1871921D01*
X886063Y1870463D01*
X886373Y1869005D01*
X887148Y1867963D01*
X888388Y1867338D01*
X889473Y1867130D01*
G01X903733D02*
Y1879630D01*
X897998Y1870672D01*
X905748D01*
G01X914273Y1879630D02*
X913033Y1879213D01*
X912103Y1878172D01*
X911483Y1876922D01*
X911018Y1875255D01*
X910863Y1873380D01*
X911018Y1871505D01*
X911483Y1869838D01*
X912103Y1868588D01*
X913033Y1867547D01*
X914273Y1867130D01*
X915513Y1867547D01*
X916443Y1868588D01*
X917063Y1869838D01*
X917528Y1871505D01*
X917683Y1873380D01*
X917528Y1875255D01*
X917063Y1876922D01*
X916443Y1878172D01*
X915513Y1879213D01*
X914273Y1879630D01*
G01X924038Y1868588D02*
X925123Y1867547D01*
X926363Y1867130D01*
X927603Y1867547D01*
X928688Y1868796D01*
X929463Y1870672D01*
X929773Y1872547D01*
Y1874838D01*
X929463Y1876713D01*
X928688Y1878380D01*
X927758Y1879213D01*
X926673Y1879630D01*
X925433Y1879213D01*
X924503Y1878380D01*
X923883Y1877130D01*
X923573Y1875463D01*
X923883Y1874005D01*
X924658Y1872547D01*
X925588Y1871713D01*
X926673Y1871505D01*
X927913Y1871921D01*
X928843Y1872963D01*
X929773Y1874838D01*
G01X939073Y1866713D02*
X938763Y1866922D01*
Y1867338D01*
X939073Y1867547D01*
X939383Y1867338D01*
Y1866922D01*
X939073Y1866713D01*
G01X953333Y1867130D02*
Y1879630D01*
X947598Y1870672D01*
X955348D01*
G01X960463Y1869005D02*
X961393Y1867963D01*
X962478Y1867338D01*
X963873Y1867130D01*
X965268Y1867547D01*
X966353Y1868380D01*
X967128Y1869838D01*
X967283Y1871505D01*
X966973Y1873172D01*
X966198Y1874213D01*
X965113Y1875047D01*
X964028Y1875255D01*
X962943Y1875047D01*
X961548Y1874213D01*
X962013Y1879630D01*
X966198D01*
G01X897683Y1842130D02*
Y1854630D01*
X891948Y1845672D01*
X899698D01*
G01X905278Y1847338D02*
X906363Y1848797D01*
X907293Y1849630D01*
X908533Y1850047D01*
X909618Y1849630D01*
X910393Y1848797D01*
X911013Y1847547D01*
X911168Y1846088D01*
X911013Y1844838D01*
X910393Y1843588D01*
X909463Y1842547D01*
X908378Y1842130D01*
X907138Y1842547D01*
X906053Y1843796D01*
X905433Y1845672D01*
X905278Y1847755D01*
X905588Y1850463D01*
X906053Y1851922D01*
X906828Y1853380D01*
X907913Y1854422D01*
X908998Y1854630D01*
X910083Y1854213D01*
X910858Y1853172D01*
G01X920313Y1842130D02*
X920623Y1844838D01*
X921088Y1847130D01*
X921708Y1849213D01*
X922483Y1851505D01*
X923723Y1854630D01*
X917523D01*
G01X933023Y1841713D02*
X932713Y1841922D01*
Y1842338D01*
X933023Y1842547D01*
X933333Y1842338D01*
Y1841922D01*
X933023Y1841713D01*
G01X942478Y1847338D02*
X943563Y1848797D01*
X944493Y1849630D01*
X945733Y1850047D01*
X946818Y1849630D01*
X947593Y1848797D01*
X948213Y1847547D01*
X948368Y1846088D01*
X948213Y1844838D01*
X947593Y1843588D01*
X946663Y1842547D01*
X945578Y1842130D01*
X944338Y1842547D01*
X943253Y1843796D01*
X942633Y1845672D01*
X942478Y1847755D01*
X942788Y1850463D01*
X943253Y1851922D01*
X944028Y1853380D01*
X945113Y1854422D01*
X946198Y1854630D01*
X947283Y1854213D01*
X948058Y1853172D01*
G01X1779922Y1801195D02*
G03I-5906J0D01*
G01X1827510Y-83298D02*
G03I-6250J0D01*
G01Y1801195D02*
G03I-6250J0D01*
G01X1874695Y815549D02*
X1862195D01*
X1864695Y813689D01*
G01X1874695D02*
Y817409D01*
G01X1873237Y825314D02*
X1874278Y826399D01*
X1874695Y827639D01*
X1874278Y828879D01*
X1873029Y829964D01*
X1871153Y830739D01*
X1869278Y831049D01*
X1866987D01*
X1865112Y830739D01*
X1863445Y829964D01*
X1862612Y829034D01*
X1862195Y827949D01*
X1862612Y826709D01*
X1863445Y825779D01*
X1864695Y825159D01*
X1866362Y824849D01*
X1867820Y825159D01*
X1869278Y825934D01*
X1870112Y826864D01*
X1870320Y827949D01*
X1869904Y829189D01*
X1868862Y830119D01*
X1866987Y831049D01*
G01X1864278Y837404D02*
X1863029Y838334D01*
X1862403Y839419D01*
X1862195Y840659D01*
X1862612Y842209D01*
X1863653Y843294D01*
X1864903Y843604D01*
X1866154Y843449D01*
X1867195Y842829D01*
X1869278Y839729D01*
X1870737Y838334D01*
X1872820Y837404D01*
X1874695Y837094D01*
Y843604D01*
G01X1872195Y849339D02*
X1873654Y850269D01*
X1874487Y851509D01*
X1874695Y852904D01*
X1874487Y854144D01*
X1873445Y855384D01*
X1872195Y856159D01*
X1870945Y856314D01*
X1869487Y856004D01*
X1868445Y854919D01*
X1868028Y853834D01*
Y852439D01*
G01Y853834D02*
X1867403Y854764D01*
X1866362Y855539D01*
X1865112Y855849D01*
X1863862Y855539D01*
X1862820Y854764D01*
X1862195Y853369D01*
X1862403Y851974D01*
X1863237Y850579D01*
G01X1874695Y865149D02*
X1874487Y866234D01*
X1873862Y867474D01*
X1872820Y868249D01*
X1871362Y868559D01*
X1869904Y868249D01*
X1868653Y867319D01*
X1868028Y865924D01*
Y864374D01*
X1867612Y863444D01*
X1866570Y862669D01*
X1865112Y862359D01*
X1863653Y862824D01*
X1862612Y863909D01*
X1862195Y865149D01*
X1862612Y866389D01*
X1863653Y867474D01*
X1865112Y867939D01*
X1866570Y867629D01*
X1867612Y866854D01*
X1868028Y865924D01*
Y864374D01*
X1868653Y862979D01*
X1869904Y862049D01*
X1871362Y861739D01*
X1872820Y862049D01*
X1873862Y862824D01*
X1874487Y864064D01*
X1874695Y865149D01*
G01X1875112Y877549D02*
X1874903Y877239D01*
X1874487D01*
X1874278Y877549D01*
X1874487Y877859D01*
X1874903D01*
X1875112Y877549D01*
G01X1869487Y887004D02*
X1868028Y888089D01*
X1867195Y889019D01*
X1866778Y890259D01*
X1867195Y891344D01*
X1868028Y892119D01*
X1869278Y892739D01*
X1870737Y892894D01*
X1871987Y892739D01*
X1873237Y892119D01*
X1874278Y891189D01*
X1874695Y890104D01*
X1874278Y888864D01*
X1873029Y887779D01*
X1871153Y887159D01*
X1869070Y887004D01*
X1866362Y887314D01*
X1864903Y887779D01*
X1863445Y888554D01*
X1862403Y889639D01*
X1862195Y890724D01*
X1862612Y891809D01*
X1863653Y892584D01*
G01X1872195Y898939D02*
X1873654Y899869D01*
X1874487Y901109D01*
X1874695Y902504D01*
X1874487Y903744D01*
X1873445Y904984D01*
X1872195Y905759D01*
X1870945Y905914D01*
X1869487Y905604D01*
X1868445Y904519D01*
X1868028Y903434D01*
Y902039D01*
G01Y903434D02*
X1867403Y904364D01*
X1866362Y905139D01*
X1865112Y905449D01*
X1863862Y905139D01*
X1862820Y904364D01*
X1862195Y902969D01*
X1862403Y901574D01*
X1863237Y900179D01*
G01X1899695Y829959D02*
X1887195D01*
X1896153Y824224D01*
Y831974D01*
G01X1899695Y840499D02*
X1899487Y841584D01*
X1898862Y842824D01*
X1897820Y843599D01*
X1896362Y843909D01*
X1894904Y843599D01*
X1893653Y842669D01*
X1893028Y841274D01*
Y839724D01*
X1892612Y838794D01*
X1891570Y838019D01*
X1890112Y837709D01*
X1888653Y838174D01*
X1887612Y839259D01*
X1887195Y840499D01*
X1887612Y841739D01*
X1888653Y842824D01*
X1890112Y843289D01*
X1891570Y842979D01*
X1892612Y842204D01*
X1893028Y841274D01*
Y839724D01*
X1893653Y838329D01*
X1894904Y837399D01*
X1896362Y837089D01*
X1897820Y837399D01*
X1898862Y838174D01*
X1899487Y839414D01*
X1899695Y840499D01*
G01Y852899D02*
X1899487Y853984D01*
X1898862Y855224D01*
X1897820Y855999D01*
X1896362Y856309D01*
X1894904Y855999D01*
X1893653Y855069D01*
X1893028Y853674D01*
Y852124D01*
X1892612Y851194D01*
X1891570Y850419D01*
X1890112Y850109D01*
X1888653Y850574D01*
X1887612Y851659D01*
X1887195Y852899D01*
X1887612Y854139D01*
X1888653Y855224D01*
X1890112Y855689D01*
X1891570Y855379D01*
X1892612Y854604D01*
X1893028Y853674D01*
Y852124D01*
X1893653Y850729D01*
X1894904Y849799D01*
X1896362Y849489D01*
X1897820Y849799D01*
X1898862Y850574D01*
X1899487Y851814D01*
X1899695Y852899D01*
G01X1900112Y865299D02*
X1899903Y864989D01*
X1899487D01*
X1899278Y865299D01*
X1899487Y865609D01*
X1899903D01*
X1900112Y865299D01*
G01X1894487Y874754D02*
X1893028Y875839D01*
X1892195Y876769D01*
X1891778Y878009D01*
X1892195Y879094D01*
X1893028Y879869D01*
X1894278Y880489D01*
X1895737Y880644D01*
X1896987Y880489D01*
X1898237Y879869D01*
X1899278Y878939D01*
X1899695Y877854D01*
X1899278Y876614D01*
X1898029Y875529D01*
X1896153Y874909D01*
X1894070Y874754D01*
X1891362Y875064D01*
X1889903Y875529D01*
X1888445Y876304D01*
X1887403Y877389D01*
X1887195Y878474D01*
X1887612Y879559D01*
X1888653Y880334D01*
G01X1894487Y887154D02*
X1893028Y888239D01*
X1892195Y889169D01*
X1891778Y890409D01*
X1892195Y891494D01*
X1893028Y892269D01*
X1894278Y892889D01*
X1895737Y893044D01*
X1896987Y892889D01*
X1898237Y892269D01*
X1899278Y891339D01*
X1899695Y890254D01*
X1899278Y889014D01*
X1898029Y887929D01*
X1896153Y887309D01*
X1894070Y887154D01*
X1891362Y887464D01*
X1889903Y887929D01*
X1888445Y888704D01*
X1887403Y889789D01*
X1887195Y890874D01*
X1887612Y891959D01*
X1888653Y892734D01*
G01X2152774Y286509D02*
X2397183D01*
Y2494D01*
X2152774D01*
Y286509D01*
G01X2200018Y135084D02*
G03I-5906J0D01*
G01X2199811Y233587D02*
G03I-6250J0D01*
G01X2208286Y61856D02*
X2217734D01*
G02Y53982I0J-3937D01*
G01X2208286D01*
G01X2237419Y61856D02*
X2246868D01*
G01X2237419D02*
G03Y53982I0J-3937D01*
G01X2246868D01*
M02*
